(kicad_sch
	(version 20250114)
	(generator "eeschema")
	(generator_version "9.0")
	(paper "A3")
	(title_block
		(title "RDIMM DDR5 Tester")
		(date "2026-05-21")
		(rev "2.2.0")
		(company "Antmicro")
		(comment 1 "www.antmicro.com")
		(comment 2 "Antmicro")
	)
	(text "Bootstrap configuration"
		(exclude_from_sim no)
		(at 262.89 142.24 0)
		(effects
			(font
				(size 2 2)
				(thickness 0.4)
				(bold yes)
			)
			(justify left bottom)
		)
	)
	(text "PHYAD2"
		(exclude_from_sim no)
		(at 338.455 171.45 0)
		(effects
			(font
				(size 1.27 1.27)
			)
			(justify left bottom)
		)
	)
	(text "CLK125_EN"
		(exclude_from_sim no)
		(at 337.82 179.705 0)
		(effects
			(font
				(size 1.27 1.27)
			)
			(justify left bottom)
		)
	)
	(text "MODE2"
		(exclude_from_sim no)
		(at 338.455 162.56 0)
		(effects
			(font
				(size 1.27 1.27)
			)
			(justify left bottom)
		)
	)
	(text "Ethernet PHY"
		(exclude_from_sim no)
		(at 17.78 25.4 0)
		(effects
			(font
				(size 2 2)
				(thickness 0.4)
				(bold yes)
			)
			(justify left bottom)
		)
	)
	(text "Reference plane decoupling"
		(exclude_from_sim no)
		(at 262.89 217.17 0)
		(effects
			(font
				(size 2 2)
				(thickness 0.4)
				(bold yes)
			)
			(justify left bottom)
		)
	)
	(text "PHYAD1"
		(exclude_from_sim no)
		(at 338.455 173.99 0)
		(effects
			(font
				(size 1.27 1.27)
			)
			(justify left bottom)
		)
	)
	(text "MODE[3:0] : 1100 (RGMII mode - Advertise 1000BASE-T full-duplex only)\nPHYAD[4:0]: 00011 \nCLK125_EN: 0, disabled\nLED_MODE: 1,  Single-LED mode\n"
		(exclude_from_sim no)
		(at 299.72 203.2 0)
		(effects
			(font
				(size 1.27 1.27)
			)
			(justify left bottom)
		)
	)
	(text "RJ45 connector"
		(exclude_from_sim no)
		(at 264.16 20.32 0)
		(effects
			(font
				(size 2 2)
				(thickness 0.4)
				(bold yes)
			)
			(justify left bottom)
		)
	)
	(text "Gigabit Ethernet"
		(exclude_from_sim no)
		(at 16.51 20.32 0)
		(effects
			(font
				(size 3 3)
				(thickness 0.6)
				(bold yes)
			)
			(justify left bottom)
		)
	)
	(text "MODE3"
		(exclude_from_sim no)
		(at 338.455 160.02 0)
		(effects
			(font
				(size 1.27 1.27)
			)
			(justify left bottom)
		)
	)
	(text "MODE1"
		(exclude_from_sim no)
		(at 338.455 165.1 0)
		(effects
			(font
				(size 1.27 1.27)
			)
			(justify left bottom)
		)
	)
	(text "MODE0\n"
		(exclude_from_sim no)
		(at 338.455 167.64 0)
		(effects
			(font
				(size 1.27 1.27)
			)
			(justify left bottom)
		)
	)
	(text "LED_MODE"
		(exclude_from_sim no)
		(at 337.82 182.245 0)
		(effects
			(font
				(size 1.27 1.27)
			)
			(justify left bottom)
		)
	)
	(text "PHYAD0"
		(exclude_from_sim no)
		(at 338.455 176.53 0)
		(effects
			(font
				(size 1.27 1.27)
			)
			(justify left bottom)
		)
	)
	(junction
		(at 191.77 105.41)
		(diameter 0)
		(color 0 0 0 0)
	)
	(junction
		(at 300.99 176.53)
		(diameter 0)
		(color 0 0 0 0)
	)
	(junction
		(at 300.99 171.45)
		(diameter 0)
		(color 0 0 0 0)
	)
	(junction
		(at 300.99 168.91)
		(diameter 0)
		(color 0 0 0 0)
	)
	(junction
		(at 191.77 127)
		(diameter 0)
		(color 0 0 0 0)
	)
	(junction
		(at 62.23 140.97)
		(diameter 0)
		(color 0 0 0 0)
	)
	(junction
		(at 241.3 105.41)
		(diameter 0)
		(color 0 0 0 0)
	)
	(junction
		(at 245.11 127)
		(diameter 0)
		(color 0 0 0 0)
	)
	(junction
		(at 245.11 105.41)
		(diameter 0)
		(color 0 0 0 0)
	)
	(junction
		(at 93.98 124.46)
		(diameter 0)
		(color 0 0 0 0)
	)
	(junction
		(at 228.6 142.24)
		(diameter 0)
		(color 0 0 0 0)
	)
	(junction
		(at 38.1 124.46)
		(diameter 0)
		(color 0 0 0 0)
	)
	(junction
		(at 372.11 168.91)
		(diameter 0)
		(color 0 0 0 0)
	)
	(junction
		(at 86.36 201.93)
		(diameter 0)
		(color 0 0 0 0)
	)
	(junction
		(at 300.99 163.83)
		(diameter 0)
		(color 0 0 0 0)
	)
	(junction
		(at 300.99 166.37)
		(diameter 0)
		(color 0 0 0 0)
	)
	(junction
		(at 372.11 166.37)
		(diameter 0)
		(color 0 0 0 0)
	)
	(junction
		(at 100.33 193.04)
		(diameter 0)
		(color 0 0 0 0)
	)
	(junction
		(at 68.58 104.14)
		(diameter 0)
		(color 0 0 0 0)
	)
	(junction
		(at 182.88 127)
		(diameter 0)
		(color 0 0 0 0)
	)
	(junction
		(at 182.88 142.24)
		(diameter 0)
		(color 0 0 0 0)
	)
	(junction
		(at 228.6 127)
		(diameter 0)
		(color 0 0 0 0)
	)
	(junction
		(at 372.11 173.99)
		(diameter 0)
		(color 0 0 0 0)
	)
	(junction
		(at 100.33 201.93)
		(diameter 0)
		(color 0 0 0 0)
	)
	(junction
		(at 175.26 127)
		(diameter 0)
		(color 0 0 0 0)
	)
	(junction
		(at 86.36 193.04)
		(diameter 0)
		(color 0 0 0 0)
	)
	(junction
		(at 372.11 163.83)
		(diameter 0)
		(color 0 0 0 0)
	)
	(junction
		(at 175.26 142.24)
		(diameter 0)
		(color 0 0 0 0)
	)
	(junction
		(at 93.98 210.82)
		(diameter 0)
		(color 0 0 0 0)
	)
	(junction
		(at 52.07 104.14)
		(diameter 0)
		(color 0 0 0 0)
	)
	(junction
		(at 175.26 105.41)
		(diameter 0)
		(color 0 0 0 0)
	)
	(junction
		(at 85.09 104.14)
		(diameter 0)
		(color 0 0 0 0)
	)
	(junction
		(at 300.99 180.34)
		(diameter 0)
		(color 0 0 0 0)
	)
	(junction
		(at 300.99 161.29)
		(diameter 0)
		(color 0 0 0 0)
	)
	(junction
		(at 60.96 104.14)
		(diameter 0)
		(color 0 0 0 0)
	)
	(junction
		(at 156.21 193.04)
		(diameter 0)
		(color 0 0 0 0)
	)
	(junction
		(at 300.99 173.99)
		(diameter 0)
		(color 0 0 0 0)
	)
	(junction
		(at 232.41 105.41)
		(diameter 0)
		(color 0 0 0 0)
	)
	(junction
		(at 199.39 105.41)
		(diameter 0)
		(color 0 0 0 0)
	)
	(junction
		(at 77.47 104.14)
		(diameter 0)
		(color 0 0 0 0)
	)
	(junction
		(at 46.99 124.46)
		(diameter 0)
		(color 0 0 0 0)
	)
	(junction
		(at 182.88 105.41)
		(diameter 0)
		(color 0 0 0 0)
	)
	(junction
		(at 191.77 142.24)
		(diameter 0)
		(color 0 0 0 0)
	)
	(junction
		(at 199.39 127)
		(diameter 0)
		(color 0 0 0 0)
	)
	(junction
		(at 54.61 124.46)
		(diameter 0)
		(color 0 0 0 0)
	)
	(junction
		(at 224.79 105.41)
		(diameter 0)
		(color 0 0 0 0)
	)
	(junction
		(at 311.15 93.98)
		(diameter 0)
		(color 0 0 0 0)
	)
	(junction
		(at 156.21 190.5)
		(diameter 0)
		(color 0 0 0 0)
	)
	(junction
		(at 297.18 93.98)
		(diameter 0)
		(color 0 0 0 0)
	)
	(junction
		(at 215.9 105.41)
		(diameter 0)
		(color 0 0 0 0)
	)
	(junction
		(at 372.11 180.34)
		(diameter 0)
		(color 0 0 0 0)
	)
	(junction
		(at 208.28 105.41)
		(diameter 0)
		(color 0 0 0 0)
	)
	(junction
		(at 321.31 81.28)
		(diameter 0)
		(color 0 0 0 0)
	)
	(junction
		(at 372.11 182.88)
		(diameter 0)
		(color 0 0 0 0)
	)
	(junction
		(at 372.11 176.53)
		(diameter 0)
		(color 0 0 0 0)
	)
	(junction
		(at 372.11 171.45)
		(diameter 0)
		(color 0 0 0 0)
	)
	(no_connect
		(at 153.67 142.24)
	)
	(bus_entry
		(at 90.17 147.32)
		(size -2.54 2.54)
		(stroke
			(width 0)
			(type default)
		)
	)
	(bus_entry
		(at 92.71 140.97)
		(size -2.54 -2.54)
		(stroke
			(width 0)
			(type default)
		)
	)
	(bus_entry
		(at 92.71 182.88)
		(size -2.54 -2.54)
		(stroke
			(width 0)
			(type default)
		)
	)
	(bus_entry
		(at 92.71 166.37)
		(size -2.54 -2.54)
		(stroke
			(width 0)
			(type default)
		)
	)
	(bus_entry
		(at 92.71 161.29)
		(size -2.54 -2.54)
		(stroke
			(width 0)
			(type default)
		)
	)
	(bus_entry
		(at 92.71 170.18)
		(size -2.54 -2.54)
		(stroke
			(width 0)
			(type default)
		)
	)
	(bus_entry
		(at 90.17 138.43)
		(size -2.54 2.54)
		(stroke
			(width 0)
			(type default)
		)
	)
	(bus_entry
		(at 92.71 143.51)
		(size -2.54 -2.54)
		(stroke
			(width 0)
			(type default)
		)
	)
	(bus_entry
		(at 92.71 156.21)
		(size -2.54 -2.54)
		(stroke
			(width 0)
			(type default)
		)
	)
	(bus_entry
		(at 92.71 180.34)
		(size -2.54 -2.54)
		(stroke
			(width 0)
			(type default)
		)
	)
	(bus_entry
		(at 92.71 172.72)
		(size -2.54 -2.54)
		(stroke
			(width 0)
			(type default)
		)
	)
	(bus_entry
		(at 92.71 163.83)
		(size -2.54 -2.54)
		(stroke
			(width 0)
			(type default)
		)
	)
	(bus_entry
		(at 92.71 147.32)
		(size -2.54 -2.54)
		(stroke
			(width 0)
			(type default)
		)
	)
	(bus_entry
		(at 92.71 153.67)
		(size -2.54 -2.54)
		(stroke
			(width 0)
			(type default)
		)
	)
	(bus_entry
		(at 92.71 186.69)
		(size -2.54 -2.54)
		(stroke
			(width 0)
			(type default)
		)
	)
	(bus_entry
		(at 92.71 158.75)
		(size -2.54 -2.54)
		(stroke
			(width 0)
			(type default)
		)
	)
	(bus_entry
		(at 92.71 175.26)
		(size -2.54 -2.54)
		(stroke
			(width 0)
			(type default)
		)
	)
	(bus_entry
		(at 92.71 149.86)
		(size -2.54 -2.54)
		(stroke
			(width 0)
			(type default)
		)
	)
	(bus_entry
		(at 92.71 177.8)
		(size -2.54 -2.54)
		(stroke
			(width 0)
			(type default)
		)
	)
	(wire
		(pts
			(xy 100.33 210.82) (xy 93.98 210.82)
		)
		(stroke
			(width 0)
			(type default)
		)
	)
	(wire
		(pts
			(xy 191.77 133.35) (xy 191.77 134.62)
		)
		(stroke
			(width 0)
			(type default)
		)
	)
	(wire
		(pts
			(xy 166.37 142.24) (xy 166.37 139.7)
		)
		(stroke
			(width 0)
			(type default)
		)
	)
	(wire
		(pts
			(xy 92.71 182.88) (xy 109.22 182.88)
		)
		(stroke
			(width 0)
			(type default)
		)
	)
	(bus
		(pts
			(xy 90.17 147.32) (xy 90.17 151.13)
		)
		(stroke
			(width 0)
			(type default)
		)
	)
	(polyline
		(pts
			(xy 260.35 134.62) (xy 407.67 134.62)
		)
		(stroke
			(width 0)
			(type default)
		)
	)
	(wire
		(pts
			(xy 312.42 166.37) (xy 300.99 166.37)
		)
		(stroke
			(width 0)
			(type default)
		)
	)
	(wire
		(pts
			(xy 153.67 162.56) (xy 166.37 162.56)
		)
		(stroke
			(width 0)
			(type default)
		)
	)
	(wire
		(pts
			(xy 361.95 163.83) (xy 372.11 163.83)
		)
		(stroke
			(width 0)
			(type default)
		)
	)
	(wire
		(pts
			(xy 345.44 81.28) (xy 361.95 81.28)
		)
		(stroke
			(width 0)
			(type default)
		)
	)
	(wire
		(pts
			(xy 312.42 163.83) (xy 300.99 163.83)
		)
		(stroke
			(width 0)
			(type default)
		)
	)
	(bus
		(pts
			(xy 90.17 140.97) (xy 90.17 144.78)
		)
		(stroke
			(width 0)
			(type default)
		)
	)
	(wire
		(pts
			(xy 153.67 139.7) (xy 166.37 139.7)
		)
		(stroke
			(width 0)
			(type default)
		)
	)
	(wire
		(pts
			(xy 307.34 58.42) (xy 322.58 58.42)
		)
		(stroke
			(width 0)
			(type default)
		)
	)
	(bus
		(pts
			(xy 90.17 156.21) (xy 90.17 158.75)
		)
		(stroke
			(width 0)
			(type default)
		)
	)
	(wire
		(pts
			(xy 92.71 156.21) (xy 109.22 156.21)
		)
		(stroke
			(width 0)
			(type default)
		)
	)
	(wire
		(pts
			(xy 60.96 104.14) (xy 60.96 106.68)
		)
		(stroke
			(width 0)
			(type default)
		)
	)
	(wire
		(pts
			(xy 86.36 210.82) (xy 86.36 208.28)
		)
		(stroke
			(width 0)
			(type default)
		)
	)
	(wire
		(pts
			(xy 199.39 128.27) (xy 199.39 127)
		)
		(stroke
			(width 0)
			(type default)
		)
	)
	(wire
		(pts
			(xy 300.99 180.34) (xy 300.99 182.88)
		)
		(stroke
			(width 0)
			(type default)
		)
	)
	(wire
		(pts
			(xy 208.28 113.03) (xy 208.28 114.3)
		)
		(stroke
			(width 0)
			(type default)
		)
	)
	(wire
		(pts
			(xy 175.26 142.24) (xy 175.26 144.78)
		)
		(stroke
			(width 0)
			(type default)
		)
	)
	(wire
		(pts
			(xy 199.39 133.35) (xy 199.39 134.62)
		)
		(stroke
			(width 0)
			(type default)
		)
	)
	(wire
		(pts
			(xy 86.36 193.04) (xy 86.36 190.5)
		)
		(stroke
			(width 0)
			(type default)
		)
	)
	(bus
		(pts
			(xy 90.17 144.78) (xy 90.17 147.32)
		)
		(stroke
			(width 0)
			(type default)
		)
	)
	(wire
		(pts
			(xy 224.79 113.03) (xy 224.79 114.3)
		)
		(stroke
			(width 0)
			(type default)
		)
	)
	(wire
		(pts
			(xy 337.82 231.14) (xy 337.82 232.41)
		)
		(stroke
			(width 0)
			(type default)
		)
	)
	(wire
		(pts
			(xy 153.67 168.91) (xy 166.37 168.91)
		)
		(stroke
			(width 0)
			(type default)
		)
	)
	(wire
		(pts
			(xy 321.31 85.09) (xy 321.31 81.28)
		)
		(stroke
			(width 0)
			(type default)
		)
	)
	(wire
		(pts
			(xy 311.15 93.98) (xy 311.15 95.25)
		)
		(stroke
			(width 0)
			(type default)
		)
	)
	(wire
		(pts
			(xy 38.1 133.35) (xy 38.1 134.62)
		)
		(stroke
			(width 0)
			(type default)
		)
	)
	(wire
		(pts
			(xy 46.99 124.46) (xy 54.61 124.46)
		)
		(stroke
			(width 0)
			(type default)
		)
	)
	(wire
		(pts
			(xy 312.42 161.29) (xy 300.99 161.29)
		)
		(stroke
			(width 0)
			(type default)
		)
	)
	(bus
		(pts
			(xy 88.9 135.89) (xy 90.17 137.16)
		)
		(stroke
			(width 0)
			(type default)
		)
	)
	(wire
		(pts
			(xy 317.5 180.34) (xy 356.87 180.34)
		)
		(stroke
			(width 0)
			(type default)
		)
	)
	(wire
		(pts
			(xy 153.67 160.02) (xy 166.37 160.02)
		)
		(stroke
			(width 0)
			(type default)
		)
	)
	(wire
		(pts
			(xy 300.99 166.37) (xy 300.99 168.91)
		)
		(stroke
			(width 0)
			(type default)
		)
	)
	(wire
		(pts
			(xy 361.95 161.29) (xy 372.11 161.29)
		)
		(stroke
			(width 0)
			(type default)
		)
	)
	(wire
		(pts
			(xy 208.28 105.41) (xy 208.28 107.95)
		)
		(stroke
			(width 0)
			(type default)
		)
	)
	(wire
		(pts
			(xy 71.12 149.86) (xy 87.63 149.86)
		)
		(stroke
			(width 0)
			(type default)
		)
	)
	(wire
		(pts
			(xy 311.15 93.98) (xy 311.15 90.17)
		)
		(stroke
			(width 0)
			(type default)
		)
	)
	(wire
		(pts
			(xy 92.71 170.18) (xy 109.22 170.18)
		)
		(stroke
			(width 0)
			(type default)
		)
	)
	(wire
		(pts
			(xy 92.71 175.26) (xy 109.22 175.26)
		)
		(stroke
			(width 0)
			(type default)
		)
	)
	(wire
		(pts
			(xy 52.07 104.14) (xy 52.07 106.68)
		)
		(stroke
			(width 0)
			(type default)
		)
	)
	(wire
		(pts
			(xy 317.5 171.45) (xy 356.87 171.45)
		)
		(stroke
			(width 0)
			(type default)
		)
	)
	(wire
		(pts
			(xy 361.95 173.99) (xy 372.11 173.99)
		)
		(stroke
			(width 0)
			(type default)
		)
	)
	(wire
		(pts
			(xy 85.09 104.14) (xy 107.95 104.14)
		)
		(stroke
			(width 0)
			(type default)
		)
	)
	(bus
		(pts
			(xy 86.36 135.89) (xy 88.9 135.89)
		)
		(stroke
			(width 0)
			(type default)
		)
	)
	(wire
		(pts
			(xy 297.18 93.98) (xy 297.18 95.25)
		)
		(stroke
			(width 0)
			(type default)
		)
	)
	(wire
		(pts
			(xy 297.18 74.93) (xy 322.58 74.93)
		)
		(stroke
			(width 0)
			(type default)
		)
	)
	(wire
		(pts
			(xy 93.98 207.01) (xy 93.98 210.82)
		)
		(stroke
			(width 0)
			(type default)
		)
	)
	(wire
		(pts
			(xy 107.95 133.35) (xy 109.22 133.35)
		)
		(stroke
			(width 0)
			(type default)
		)
	)
	(wire
		(pts
			(xy 312.42 180.34) (xy 300.99 180.34)
		)
		(stroke
			(width 0)
			(type default)
		)
	)
	(wire
		(pts
			(xy 93.98 137.16) (xy 109.22 137.16)
		)
		(stroke
			(width 0)
			(type default)
		)
	)
	(wire
		(pts
			(xy 92.71 177.8) (xy 109.22 177.8)
		)
		(stroke
			(width 0)
			(type default)
		)
	)
	(wire
		(pts
			(xy 242.57 142.24) (xy 245.11 142.24)
		)
		(stroke
			(width 0)
			(type default)
		)
	)
	(wire
		(pts
			(xy 175.26 142.24) (xy 182.88 142.24)
		)
		(stroke
			(width 0)
			(type default)
		)
	)
	(wire
		(pts
			(xy 372.11 166.37) (xy 372.11 168.91)
		)
		(stroke
			(width 0)
			(type default)
		)
	)
	(wire
		(pts
			(xy 241.3 105.41) (xy 245.11 105.41)
		)
		(stroke
			(width 0)
			(type default)
		)
	)
	(wire
		(pts
			(xy 30.48 124.46) (xy 25.4 124.46)
		)
		(stroke
			(width 0)
			(type default)
		)
	)
	(wire
		(pts
			(xy 35.56 124.46) (xy 38.1 124.46)
		)
		(stroke
			(width 0)
			(type default)
		)
	)
	(wire
		(pts
			(xy 326.39 238.76) (xy 326.39 237.49)
		)
		(stroke
			(width 0)
			(type default)
		)
	)
	(wire
		(pts
			(xy 182.88 127) (xy 191.77 127)
		)
		(stroke
			(width 0)
			(type default)
		)
	)
	(wire
		(pts
			(xy 92.71 180.34) (xy 109.22 180.34)
		)
		(stroke
			(width 0)
			(type default)
		)
	)
	(polyline
		(pts
			(xy 260.35 12.7) (xy 260.35 284.48)
		)
		(stroke
			(width 0)
			(type default)
		)
	)
	(wire
		(pts
			(xy 92.71 172.72) (xy 109.22 172.72)
		)
		(stroke
			(width 0)
			(type default)
		)
	)
	(wire
		(pts
			(xy 175.26 105.41) (xy 182.88 105.41)
		)
		(stroke
			(width 0)
			(type default)
		)
	)
	(wire
		(pts
			(xy 66.04 149.86) (xy 62.23 149.86)
		)
		(stroke
			(width 0)
			(type default)
		)
	)
	(polyline
		(pts
			(xy 260.35 209.55) (xy 407.67 209.55)
		)
		(stroke
			(width 0)
			(type default)
		)
	)
	(wire
		(pts
			(xy 307.34 68.58) (xy 322.58 68.58)
		)
		(stroke
			(width 0)
			(type default)
		)
	)
	(wire
		(pts
			(xy 163.83 177.8) (xy 153.67 177.8)
		)
		(stroke
			(width 0)
			(type default)
		)
	)
	(wire
		(pts
			(xy 86.36 210.82) (xy 93.98 210.82)
		)
		(stroke
			(width 0)
			(type default)
		)
	)
	(bus
		(pts
			(xy 90.17 137.16) (xy 90.17 138.43)
		)
		(stroke
			(width 0)
			(type default)
		)
	)
	(wire
		(pts
			(xy 62.23 138.43) (xy 62.23 140.97)
		)
		(stroke
			(width 0)
			(type default)
		)
	)
	(wire
		(pts
			(xy 182.88 142.24) (xy 182.88 144.78)
		)
		(stroke
			(width 0)
			(type default)
		)
	)
	(wire
		(pts
			(xy 245.11 100.33) (xy 245.11 105.41)
		)
		(stroke
			(width 0)
			(type default)
		)
	)
	(wire
		(pts
			(xy 312.42 176.53) (xy 300.99 176.53)
		)
		(stroke
			(width 0)
			(type default)
		)
	)
	(wire
		(pts
			(xy 54.61 124.46) (xy 93.98 124.46)
		)
		(stroke
			(width 0)
			(type default)
		)
	)
	(wire
		(pts
			(xy 77.47 111.76) (xy 77.47 113.03)
		)
		(stroke
			(width 0)
			(type default)
		)
	)
	(wire
		(pts
			(xy 85.09 104.14) (xy 77.47 104.14)
		)
		(stroke
			(width 0)
			(type default)
		)
	)
	(wire
		(pts
			(xy 153.67 166.37) (xy 166.37 166.37)
		)
		(stroke
			(width 0)
			(type default)
		)
	)
	(wire
		(pts
			(xy 361.95 168.91) (xy 372.11 168.91)
		)
		(stroke
			(width 0)
			(type default)
		)
	)
	(wire
		(pts
			(xy 300.99 158.75) (xy 300.99 161.29)
		)
		(stroke
			(width 0)
			(type default)
		)
	)
	(wire
		(pts
			(xy 312.42 182.88) (xy 300.99 182.88)
		)
		(stroke
			(width 0)
			(type default)
		)
	)
	(wire
		(pts
			(xy 166.37 127) (xy 175.26 127)
		)
		(stroke
			(width 0)
			(type default)
		)
	)
	(bus
		(pts
			(xy 90.17 180.34) (xy 90.17 184.15)
		)
		(stroke
			(width 0)
			(type default)
		)
	)
	(wire
		(pts
			(xy 191.77 127) (xy 191.77 128.27)
		)
		(stroke
			(width 0)
			(type default)
		)
	)
	(wire
		(pts
			(xy 372.11 180.34) (xy 372.11 182.88)
		)
		(stroke
			(width 0)
			(type default)
		)
	)
	(wire
		(pts
			(xy 156.21 193.04) (xy 156.21 195.58)
		)
		(stroke
			(width 0)
			(type default)
		)
	)
	(wire
		(pts
			(xy 153.67 137.16) (xy 166.37 137.16)
		)
		(stroke
			(width 0)
			(type default)
		)
	)
	(wire
		(pts
			(xy 99.06 124.46) (xy 99.06 121.92)
		)
		(stroke
			(width 0)
			(type default)
		)
	)
	(wire
		(pts
			(xy 232.41 105.41) (xy 241.3 105.41)
		)
		(stroke
			(width 0)
			(type default)
		)
	)
	(wire
		(pts
			(xy 300.99 171.45) (xy 300.99 173.99)
		)
		(stroke
			(width 0)
			(type default)
		)
	)
	(bus
		(pts
			(xy 90.17 138.43) (xy 90.17 140.97)
		)
		(stroke
			(width 0)
			(type default)
		)
	)
	(wire
		(pts
			(xy 372.11 173.99) (xy 372.11 176.53)
		)
		(stroke
			(width 0)
			(type default)
		)
	)
	(wire
		(pts
			(xy 317.5 166.37) (xy 356.87 166.37)
		)
		(stroke
			(width 0)
			(type default)
		)
	)
	(wire
		(pts
			(xy 38.1 124.46) (xy 46.99 124.46)
		)
		(stroke
			(width 0)
			(type default)
		)
	)
	(wire
		(pts
			(xy 312.42 173.99) (xy 300.99 173.99)
		)
		(stroke
			(width 0)
			(type default)
		)
	)
	(bus
		(pts
			(xy 90.17 170.18) (xy 90.17 172.72)
		)
		(stroke
			(width 0)
			(type default)
		)
	)
	(wire
		(pts
			(xy 307.34 60.96) (xy 322.58 60.96)
		)
		(stroke
			(width 0)
			(type default)
		)
	)
	(wire
		(pts
			(xy 317.5 163.83) (xy 356.87 163.83)
		)
		(stroke
			(width 0)
			(type default)
		)
	)
	(wire
		(pts
			(xy 46.99 133.35) (xy 46.99 134.62)
		)
		(stroke
			(width 0)
			(type default)
		)
	)
	(wire
		(pts
			(xy 166.37 137.16) (xy 166.37 127)
		)
		(stroke
			(width 0)
			(type default)
		)
	)
	(wire
		(pts
			(xy 361.95 52.07) (xy 361.95 53.34)
		)
		(stroke
			(width 0)
			(type default)
		)
	)
	(wire
		(pts
			(xy 182.88 105.41) (xy 182.88 107.95)
		)
		(stroke
			(width 0)
			(type default)
		)
	)
	(wire
		(pts
			(xy 153.67 149.86) (xy 166.37 149.86)
		)
		(stroke
			(width 0)
			(type default)
		)
	)
	(bus
		(pts
			(xy 90.17 163.83) (xy 90.17 167.64)
		)
		(stroke
			(width 0)
			(type default)
		)
	)
	(wire
		(pts
			(xy 93.98 124.46) (xy 99.06 124.46)
		)
		(stroke
			(width 0)
			(type default)
		)
	)
	(wire
		(pts
			(xy 232.41 113.03) (xy 232.41 114.3)
		)
		(stroke
			(width 0)
			(type default)
		)
	)
	(wire
		(pts
			(xy 93.98 210.82) (xy 93.98 212.09)
		)
		(stroke
			(width 0)
			(type default)
		)
	)
	(wire
		(pts
			(xy 86.36 203.2) (xy 86.36 201.93)
		)
		(stroke
			(width 0)
			(type default)
		)
	)
	(wire
		(pts
			(xy 175.26 149.86) (xy 175.26 151.13)
		)
		(stroke
			(width 0)
			(type default)
		)
	)
	(wire
		(pts
			(xy 87.63 140.97) (xy 71.12 140.97)
		)
		(stroke
			(width 0)
			(type default)
		)
	)
	(wire
		(pts
			(xy 337.82 238.76) (xy 337.82 237.49)
		)
		(stroke
			(width 0)
			(type default)
		)
	)
	(wire
		(pts
			(xy 175.26 105.41) (xy 175.26 107.95)
		)
		(stroke
			(width 0)
			(type default)
		)
	)
	(wire
		(pts
			(xy 86.36 201.93) (xy 90.17 201.93)
		)
		(stroke
			(width 0)
			(type default)
		)
	)
	(wire
		(pts
			(xy 361.95 166.37) (xy 372.11 166.37)
		)
		(stroke
			(width 0)
			(type default)
		)
	)
	(wire
		(pts
			(xy 345.44 78.74) (xy 347.98 78.74)
		)
		(stroke
			(width 0)
			(type default)
		)
	)
	(wire
		(pts
			(xy 191.77 113.03) (xy 191.77 114.3)
		)
		(stroke
			(width 0)
			(type default)
		)
	)
	(wire
		(pts
			(xy 345.44 53.34) (xy 347.98 53.34)
		)
		(stroke
			(width 0)
			(type default)
		)
	)
	(wire
		(pts
			(xy 311.15 81.28) (xy 311.15 85.09)
		)
		(stroke
			(width 0)
			(type default)
		)
	)
	(wire
		(pts
			(xy 52.07 100.33) (xy 52.07 104.14)
		)
		(stroke
			(width 0)
			(type default)
		)
	)
	(wire
		(pts
			(xy 182.88 133.35) (xy 182.88 134.62)
		)
		(stroke
			(width 0)
			(type default)
		)
	)
	(wire
		(pts
			(xy 241.3 105.41) (xy 241.3 107.95)
		)
		(stroke
			(width 0)
			(type default)
		)
	)
	(wire
		(pts
			(xy 297.18 93.98) (xy 300.99 93.98)
		)
		(stroke
			(width 0)
			(type default)
		)
	)
	(wire
		(pts
			(xy 153.67 156.21) (xy 166.37 156.21)
		)
		(stroke
			(width 0)
			(type default)
		)
	)
	(wire
		(pts
			(xy 228.6 142.24) (xy 237.49 142.24)
		)
		(stroke
			(width 0)
			(type default)
		)
	)
	(wire
		(pts
			(xy 191.77 105.41) (xy 191.77 107.95)
		)
		(stroke
			(width 0)
			(type default)
		)
	)
	(wire
		(pts
			(xy 60.96 104.14) (xy 52.07 104.14)
		)
		(stroke
			(width 0)
			(type default)
		)
	)
	(wire
		(pts
			(xy 317.5 173.99) (xy 356.87 173.99)
		)
		(stroke
			(width 0)
			(type default)
		)
	)
	(wire
		(pts
			(xy 361.95 78.74) (xy 361.95 76.2)
		)
		(stroke
			(width 0)
			(type default)
		)
	)
	(wire
		(pts
			(xy 372.11 176.53) (xy 372.11 180.34)
		)
		(stroke
			(width 0)
			(type default)
		)
	)
	(wire
		(pts
			(xy 199.39 105.41) (xy 199.39 107.95)
		)
		(stroke
			(width 0)
			(type default)
		)
	)
	(bus
		(pts
			(xy 90.17 153.67) (xy 90.17 156.21)
		)
		(stroke
			(width 0)
			(type default)
		)
	)
	(wire
		(pts
			(xy 307.34 53.34) (xy 322.58 53.34)
		)
		(stroke
			(width 0)
			(type default)
		)
	)
	(wire
		(pts
			(xy 372.11 163.83) (xy 372.11 166.37)
		)
		(stroke
			(width 0)
			(type default)
		)
	)
	(wire
		(pts
			(xy 182.88 128.27) (xy 182.88 127)
		)
		(stroke
			(width 0)
			(type default)
		)
	)
	(wire
		(pts
			(xy 199.39 113.03) (xy 199.39 114.3)
		)
		(stroke
			(width 0)
			(type default)
		)
	)
	(wire
		(pts
			(xy 156.21 190.5) (xy 156.21 193.04)
		)
		(stroke
			(width 0)
			(type default)
		)
	)
	(wire
		(pts
			(xy 25.4 100.33) (xy 25.4 124.46)
		)
		(stroke
			(width 0)
			(type default)
		)
	)
	(wire
		(pts
			(xy 175.26 113.03) (xy 175.26 114.3)
		)
		(stroke
			(width 0)
			(type default)
		)
	)
	(wire
		(pts
			(xy 191.77 149.86) (xy 191.77 151.13)
		)
		(stroke
			(width 0)
			(type default)
		)
	)
	(wire
		(pts
			(xy 68.58 104.14) (xy 68.58 106.68)
		)
		(stroke
			(width 0)
			(type default)
		)
	)
	(wire
		(pts
			(xy 156.21 105.41) (xy 156.21 133.35)
		)
		(stroke
			(width 0)
			(type default)
		)
	)
	(wire
		(pts
			(xy 317.5 161.29) (xy 356.87 161.29)
		)
		(stroke
			(width 0)
			(type default)
		)
	)
	(wire
		(pts
			(xy 68.58 111.76) (xy 68.58 113.03)
		)
		(stroke
			(width 0)
			(type default)
		)
	)
	(wire
		(pts
			(xy 156.21 133.35) (xy 153.67 133.35)
		)
		(stroke
			(width 0)
			(type default)
		)
	)
	(wire
		(pts
			(xy 175.26 128.27) (xy 175.26 127)
		)
		(stroke
			(width 0)
			(type default)
		)
	)
	(wire
		(pts
			(xy 199.39 127) (xy 228.6 127)
		)
		(stroke
			(width 0)
			(type default)
		)
	)
	(wire
		(pts
			(xy 228.6 127) (xy 237.49 127)
		)
		(stroke
			(width 0)
			(type default)
		)
	)
	(wire
		(pts
			(xy 215.9 105.41) (xy 215.9 107.95)
		)
		(stroke
			(width 0)
			(type default)
		)
	)
	(wire
		(pts
			(xy 96.52 193.04) (xy 100.33 193.04)
		)
		(stroke
			(width 0)
			(type default)
		)
	)
	(wire
		(pts
			(xy 353.06 53.34) (xy 361.95 53.34)
		)
		(stroke
			(width 0)
			(type default)
		)
	)
	(wire
		(pts
			(xy 156.21 184.15) (xy 156.21 182.88)
		)
		(stroke
			(width 0)
			(type default)
		)
	)
	(wire
		(pts
			(xy 86.36 193.04) (xy 91.44 193.04)
		)
		(stroke
			(width 0)
			(type default)
		)
	)
	(wire
		(pts
			(xy 317.5 176.53) (xy 356.87 176.53)
		)
		(stroke
			(width 0)
			(type default)
		)
	)
	(wire
		(pts
			(xy 175.26 134.62) (xy 175.26 133.35)
		)
		(stroke
			(width 0)
			(type default)
		)
	)
	(wire
		(pts
			(xy 92.71 147.32) (xy 109.22 147.32)
		)
		(stroke
			(width 0)
			(type default)
		)
	)
	(wire
		(pts
			(xy 317.5 182.88) (xy 356.87 182.88)
		)
		(stroke
			(width 0)
			(type default)
		)
	)
	(wire
		(pts
			(xy 54.61 124.46) (xy 54.61 128.27)
		)
		(stroke
			(width 0)
			(type default)
		)
	)
	(wire
		(pts
			(xy 182.88 149.86) (xy 182.88 151.13)
		)
		(stroke
			(width 0)
			(type default)
		)
	)
	(wire
		(pts
			(xy 92.71 158.75) (xy 109.22 158.75)
		)
		(stroke
			(width 0)
			(type default)
		)
	)
	(wire
		(pts
			(xy 307.34 63.5) (xy 322.58 63.5)
		)
		(stroke
			(width 0)
			(type default)
		)
	)
	(wire
		(pts
			(xy 156.21 189.23) (xy 156.21 190.5)
		)
		(stroke
			(width 0)
			(type default)
		)
	)
	(wire
		(pts
			(xy 92.71 143.51) (xy 109.22 143.51)
		)
		(stroke
			(width 0)
			(type default)
		)
	)
	(wire
		(pts
			(xy 191.77 142.24) (xy 228.6 142.24)
		)
		(stroke
			(width 0)
			(type default)
		)
	)
	(wire
		(pts
			(xy 300.99 77.47) (xy 322.58 77.47)
		)
		(stroke
			(width 0)
			(type default)
		)
	)
	(wire
		(pts
			(xy 317.5 168.91) (xy 356.87 168.91)
		)
		(stroke
			(width 0)
			(type default)
		)
	)
	(wire
		(pts
			(xy 300.99 93.98) (xy 300.99 90.17)
		)
		(stroke
			(width 0)
			(type default)
		)
	)
	(wire
		(pts
			(xy 100.33 208.28) (xy 100.33 210.82)
		)
		(stroke
			(width 0)
			(type default)
		)
	)
	(wire
		(pts
			(xy 353.06 78.74) (xy 361.95 78.74)
		)
		(stroke
			(width 0)
			(type default)
		)
	)
	(wire
		(pts
			(xy 312.42 171.45) (xy 300.99 171.45)
		)
		(stroke
			(width 0)
			(type default)
		)
	)
	(wire
		(pts
			(xy 182.88 142.24) (xy 191.77 142.24)
		)
		(stroke
			(width 0)
			(type default)
		)
	)
	(wire
		(pts
			(xy 321.31 93.98) (xy 311.15 93.98)
		)
		(stroke
			(width 0)
			(type default)
		)
	)
	(wire
		(pts
			(xy 297.18 90.17) (xy 297.18 93.98)
		)
		(stroke
			(width 0)
			(type default)
		)
	)
	(wire
		(pts
			(xy 66.04 140.97) (xy 62.23 140.97)
		)
		(stroke
			(width 0)
			(type default)
		)
	)
	(wire
		(pts
			(xy 300.99 173.99) (xy 300.99 176.53)
		)
		(stroke
			(width 0)
			(type default)
		)
	)
	(wire
		(pts
			(xy 191.77 127) (xy 199.39 127)
		)
		(stroke
			(width 0)
			(type default)
		)
	)
	(wire
		(pts
			(xy 93.98 137.16) (xy 93.98 124.46)
		)
		(stroke
			(width 0)
			(type default)
		)
	)
	(wire
		(pts
			(xy 100.33 193.04) (xy 100.33 201.93)
		)
		(stroke
			(width 0)
			(type default)
		)
	)
	(wire
		(pts
			(xy 54.61 133.35) (xy 54.61 134.62)
		)
		(stroke
			(width 0)
			(type default)
		)
	)
	(wire
		(pts
			(xy 297.18 74.93) (xy 297.18 85.09)
		)
		(stroke
			(width 0)
			(type default)
		)
	)
	(wire
		(pts
			(xy 52.07 111.76) (xy 52.07 113.03)
		)
		(stroke
			(width 0)
			(type default)
		)
	)
	(wire
		(pts
			(xy 92.71 153.67) (xy 109.22 153.67)
		)
		(stroke
			(width 0)
			(type default)
		)
	)
	(wire
		(pts
			(xy 86.36 190.5) (xy 109.22 190.5)
		)
		(stroke
			(width 0)
			(type default)
		)
	)
	(bus
		(pts
			(xy 90.17 172.72) (xy 90.17 175.26)
		)
		(stroke
			(width 0)
			(type default)
		)
	)
	(wire
		(pts
			(xy 191.77 105.41) (xy 182.88 105.41)
		)
		(stroke
			(width 0)
			(type default)
		)
	)
	(bus
		(pts
			(xy 90.17 158.75) (xy 90.17 161.29)
		)
		(stroke
			(width 0)
			(type default)
		)
	)
	(bus
		(pts
			(xy 90.17 151.13) (xy 90.17 153.67)
		)
		(stroke
			(width 0)
			(type default)
		)
	)
	(wire
		(pts
			(xy 208.28 105.41) (xy 199.39 105.41)
		)
		(stroke
			(width 0)
			(type default)
		)
	)
	(wire
		(pts
			(xy 92.71 140.97) (xy 109.22 140.97)
		)
		(stroke
			(width 0)
			(type default)
		)
	)
	(wire
		(pts
			(xy 242.57 127) (xy 245.11 127)
		)
		(stroke
			(width 0)
			(type default)
		)
	)
	(wire
		(pts
			(xy 153.67 193.04) (xy 156.21 193.04)
		)
		(stroke
			(width 0)
			(type default)
		)
	)
	(wire
		(pts
			(xy 241.3 113.03) (xy 241.3 114.3)
		)
		(stroke
			(width 0)
			(type default)
		)
	)
	(bus
		(pts
			(xy 90.17 175.26) (xy 90.17 177.8)
		)
		(stroke
			(width 0)
			(type default)
		)
	)
	(wire
		(pts
			(xy 300.99 176.53) (xy 300.99 180.34)
		)
		(stroke
			(width 0)
			(type default)
		)
	)
	(wire
		(pts
			(xy 77.47 104.14) (xy 68.58 104.14)
		)
		(stroke
			(width 0)
			(type default)
		)
	)
	(wire
		(pts
			(xy 372.11 168.91) (xy 372.11 171.45)
		)
		(stroke
			(width 0)
			(type default)
		)
	)
	(wire
		(pts
			(xy 156.21 182.88) (xy 153.67 182.88)
		)
		(stroke
			(width 0)
			(type default)
		)
	)
	(wire
		(pts
			(xy 107.95 104.14) (xy 107.95 133.35)
		)
		(stroke
			(width 0)
			(type default)
		)
	)
	(wire
		(pts
			(xy 85.09 104.14) (xy 85.09 106.68)
		)
		(stroke
			(width 0)
			(type default)
		)
	)
	(wire
		(pts
			(xy 245.11 105.41) (xy 245.11 127)
		)
		(stroke
			(width 0)
			(type default)
		)
	)
	(wire
		(pts
			(xy 100.33 201.93) (xy 100.33 203.2)
		)
		(stroke
			(width 0)
			(type default)
		)
	)
	(wire
		(pts
			(xy 46.99 124.46) (xy 46.99 128.27)
		)
		(stroke
			(width 0)
			(type default)
		)
	)
	(wire
		(pts
			(xy 86.36 201.93) (xy 86.36 193.04)
		)
		(stroke
			(width 0)
			(type default)
		)
	)
	(wire
		(pts
			(xy 321.31 90.17) (xy 321.31 93.98)
		)
		(stroke
			(width 0)
			(type default)
		)
	)
	(wire
		(pts
			(xy 307.34 55.88) (xy 322.58 55.88)
		)
		(stroke
			(width 0)
			(type default)
		)
	)
	(wire
		(pts
			(xy 361.95 171.45) (xy 372.11 171.45)
		)
		(stroke
			(width 0)
			(type default)
		)
	)
	(wire
		(pts
			(xy 156.21 190.5) (xy 153.67 190.5)
		)
		(stroke
			(width 0)
			(type default)
		)
	)
	(wire
		(pts
			(xy 199.39 105.41) (xy 191.77 105.41)
		)
		(stroke
			(width 0)
			(type default)
		)
	)
	(wire
		(pts
			(xy 326.39 231.14) (xy 326.39 232.41)
		)
		(stroke
			(width 0)
			(type default)
		)
	)
	(wire
		(pts
			(xy 372.11 171.45) (xy 372.11 173.99)
		)
		(stroke
			(width 0)
			(type default)
		)
	)
	(bus
		(pts
			(xy 90.17 177.8) (xy 90.17 180.34)
		)
		(stroke
			(width 0)
			(type default)
		)
	)
	(wire
		(pts
			(xy 92.71 163.83) (xy 109.22 163.83)
		)
		(stroke
			(width 0)
			(type default)
		)
	)
	(wire
		(pts
			(xy 191.77 144.78) (xy 191.77 142.24)
		)
		(stroke
			(width 0)
			(type default)
		)
	)
	(wire
		(pts
			(xy 345.44 55.88) (xy 361.95 55.88)
		)
		(stroke
			(width 0)
			(type default)
		)
	)
	(wire
		(pts
			(xy 215.9 105.41) (xy 208.28 105.41)
		)
		(stroke
			(width 0)
			(type default)
		)
	)
	(wire
		(pts
			(xy 92.71 166.37) (xy 109.22 166.37)
		)
		(stroke
			(width 0)
			(type default)
		)
	)
	(wire
		(pts
			(xy 224.79 105.41) (xy 224.79 107.95)
		)
		(stroke
			(width 0)
			(type default)
		)
	)
	(wire
		(pts
			(xy 307.34 66.04) (xy 322.58 66.04)
		)
		(stroke
			(width 0)
			(type default)
		)
	)
	(wire
		(pts
			(xy 68.58 104.14) (xy 60.96 104.14)
		)
		(stroke
			(width 0)
			(type default)
		)
	)
	(wire
		(pts
			(xy 92.71 149.86) (xy 109.22 149.86)
		)
		(stroke
			(width 0)
			(type default)
		)
	)
	(wire
		(pts
			(xy 312.42 168.91) (xy 300.99 168.91)
		)
		(stroke
			(width 0)
			(type default)
		)
	)
	(wire
		(pts
			(xy 153.67 153.67) (xy 166.37 153.67)
		)
		(stroke
			(width 0)
			(type default)
		)
	)
	(wire
		(pts
			(xy 307.34 71.12) (xy 322.58 71.12)
		)
		(stroke
			(width 0)
			(type default)
		)
	)
	(wire
		(pts
			(xy 156.21 105.41) (xy 175.26 105.41)
		)
		(stroke
			(width 0)
			(type default)
		)
	)
	(wire
		(pts
			(xy 224.79 105.41) (xy 232.41 105.41)
		)
		(stroke
			(width 0)
			(type default)
		)
	)
	(wire
		(pts
			(xy 361.95 180.34) (xy 372.11 180.34)
		)
		(stroke
			(width 0)
			(type default)
		)
	)
	(wire
		(pts
			(xy 311.15 81.28) (xy 321.31 81.28)
		)
		(stroke
			(width 0)
			(type default)
		)
	)
	(wire
		(pts
			(xy 100.33 201.93) (xy 97.79 201.93)
		)
		(stroke
			(width 0)
			(type default)
		)
	)
	(wire
		(pts
			(xy 361.95 182.88) (xy 372.11 182.88)
		)
		(stroke
			(width 0)
			(type default)
		)
	)
	(bus
		(pts
			(xy 90.17 161.29) (xy 90.17 163.83)
		)
		(stroke
			(width 0)
			(type default)
		)
	)
	(wire
		(pts
			(xy 38.1 124.46) (xy 38.1 128.27)
		)
		(stroke
			(width 0)
			(type default)
		)
	)
	(wire
		(pts
			(xy 322.58 81.28) (xy 321.31 81.28)
		)
		(stroke
			(width 0)
			(type default)
		)
	)
	(wire
		(pts
			(xy 85.09 111.76) (xy 85.09 113.03)
		)
		(stroke
			(width 0)
			(type default)
		)
	)
	(wire
		(pts
			(xy 62.23 140.97) (xy 62.23 149.86)
		)
		(stroke
			(width 0)
			(type default)
		)
	)
	(wire
		(pts
			(xy 175.26 127) (xy 182.88 127)
		)
		(stroke
			(width 0)
			(type default)
		)
	)
	(wire
		(pts
			(xy 300.99 163.83) (xy 300.99 166.37)
		)
		(stroke
			(width 0)
			(type default)
		)
	)
	(wire
		(pts
			(xy 300.99 77.47) (xy 300.99 85.09)
		)
		(stroke
			(width 0)
			(type default)
		)
	)
	(wire
		(pts
			(xy 245.11 142.24) (xy 245.11 127)
		)
		(stroke
			(width 0)
			(type default)
		)
	)
	(wire
		(pts
			(xy 92.71 161.29) (xy 109.22 161.29)
		)
		(stroke
			(width 0)
			(type default)
		)
	)
	(wire
		(pts
			(xy 372.11 182.88) (xy 372.11 184.15)
		)
		(stroke
			(width 0)
			(type default)
		)
	)
	(wire
		(pts
			(xy 232.41 105.41) (xy 232.41 107.95)
		)
		(stroke
			(width 0)
			(type default)
		)
	)
	(bus
		(pts
			(xy 90.17 167.64) (xy 90.17 170.18)
		)
		(stroke
			(width 0)
			(type default)
		)
	)
	(wire
		(pts
			(xy 300.99 161.29) (xy 300.99 163.83)
		)
		(stroke
			(width 0)
			(type default)
		)
	)
	(wire
		(pts
			(xy 215.9 105.41) (xy 224.79 105.41)
		)
		(stroke
			(width 0)
			(type default)
		)
	)
	(wire
		(pts
			(xy 92.71 186.69) (xy 109.22 186.69)
		)
		(stroke
			(width 0)
			(type default)
		)
	)
	(wire
		(pts
			(xy 361.95 176.53) (xy 372.11 176.53)
		)
		(stroke
			(width 0)
			(type default)
		)
	)
	(wire
		(pts
			(xy 153.67 147.32) (xy 166.37 147.32)
		)
		(stroke
			(width 0)
			(type default)
		)
	)
	(wire
		(pts
			(xy 372.11 161.29) (xy 372.11 163.83)
		)
		(stroke
			(width 0)
			(type default)
		)
	)
	(wire
		(pts
			(xy 77.47 104.14) (xy 77.47 106.68)
		)
		(stroke
			(width 0)
			(type default)
		)
	)
	(wire
		(pts
			(xy 60.96 111.76) (xy 60.96 113.03)
		)
		(stroke
			(width 0)
			(type default)
		)
	)
	(wire
		(pts
			(xy 175.26 142.24) (xy 166.37 142.24)
		)
		(stroke
			(width 0)
			(type default)
		)
	)
	(wire
		(pts
			(xy 182.88 113.03) (xy 182.88 114.3)
		)
		(stroke
			(width 0)
			(type default)
		)
	)
	(wire
		(pts
			(xy 109.22 193.04) (xy 100.33 193.04)
		)
		(stroke
			(width 0)
			(type default)
		)
	)
	(wire
		(pts
			(xy 300.99 168.91) (xy 300.99 171.45)
		)
		(stroke
			(width 0)
			(type default)
		)
	)
	(wire
		(pts
			(xy 153.67 175.26) (xy 163.83 175.26)
		)
		(stroke
			(width 0)
			(type default)
		)
	)
	(wire
		(pts
			(xy 215.9 113.03) (xy 215.9 114.3)
		)
		(stroke
			(width 0)
			(type default)
		)
	)
	(label "ETH3_P"
		(at 166.37 160.02 180)
		(effects
			(font
				(size 1.27 1.27)
			)
			(justify right bottom)
		)
	)
	(label "ETH4_P"
		(at 307.34 68.58 0)
		(effects
			(font
				(size 1.27 1.27)
			)
			(justify left bottom)
		)
	)
	(label "LED_LINK"
		(at 336.55 176.53 180)
		(effects
			(font
				(size 1.27 1.27)
			)
			(justify right bottom)
		)
	)
	(label "ETH2_P"
		(at 307.34 58.42 0)
		(effects
			(font
				(size 1.27 1.27)
			)
			(justify left bottom)
		)
	)
	(label "ETH.TXD0"
		(at 92.71 156.21 0)
		(effects
			(font
				(size 1.27 1.27)
			)
			(justify left bottom)
		)
	)
	(label "ETH.RXC"
		(at 336.55 171.45 180)
		(effects
			(font
				(size 1.27 1.27)
			)
			(justify right bottom)
		)
	)
	(label "ETH.~{RESET}"
		(at 92.71 140.97 0)
		(effects
			(font
				(size 1.27 1.27)
			)
			(justify left bottom)
		)
	)
	(label "ETH3_N"
		(at 307.34 66.04 0)
		(effects
			(font
				(size 1.27 1.27)
			)
			(justify left bottom)
		)
	)
	(label "AVDDH"
		(at 102.87 137.16 180)
		(effects
			(font
				(size 1.27 1.27)
			)
			(justify right bottom)
		)
	)
	(label "ETH3_N"
		(at 166.37 162.56 180)
		(effects
			(font
				(size 1.27 1.27)
			)
			(justify right bottom)
		)
	)
	(label "ETH.RXD1"
		(at 336.55 166.37 180)
		(effects
			(font
				(size 1.27 1.27)
			)
			(justify right bottom)
		)
	)
	(label "ETH4_N"
		(at 166.37 168.91 180)
		(effects
			(font
				(size 1.27 1.27)
			)
			(justify right bottom)
		)
	)
	(label "ETH1_P"
		(at 307.34 53.34 0)
		(effects
			(font
				(size 1.27 1.27)
			)
			(justify left bottom)
		)
	)
	(label "ETH1_P"
		(at 166.37 147.32 180)
		(effects
			(font
				(size 1.27 1.27)
			)
			(justify right bottom)
		)
	)
	(label "ETH2_P"
		(at 166.37 153.67 180)
		(effects
			(font
				(size 1.27 1.27)
			)
			(justify right bottom)
		)
	)
	(label "ETH3_P"
		(at 307.34 63.5 0)
		(effects
			(font
				(size 1.27 1.27)
			)
			(justify left bottom)
		)
	)
	(label "LED_LINK"
		(at 361.95 55.88 180)
		(effects
			(font
				(size 1.27 1.27)
			)
			(justify right bottom)
		)
	)
	(label "ETH.RX_CTL"
		(at 92.71 170.18 0)
		(effects
			(font
				(size 1.27 1.27)
			)
			(justify left bottom)
		)
	)
	(label "ETH1_N"
		(at 307.34 55.88 0)
		(effects
			(font
				(size 1.27 1.27)
			)
			(justify left bottom)
		)
	)
	(label "ETH.RXC"
		(at 92.71 182.88 0)
		(effects
			(font
				(size 1.27 1.27)
			)
			(justify left bottom)
		)
	)
	(label "ETH2_N"
		(at 166.37 156.21 180)
		(effects
			(font
				(size 1.27 1.27)
			)
			(justify right bottom)
		)
	)
	(label "ETH1_N"
		(at 166.37 149.86 180)
		(effects
			(font
				(size 1.27 1.27)
			)
			(justify right bottom)
		)
	)
	(label "ETH4_N"
		(at 307.34 71.12 0)
		(effects
			(font
				(size 1.27 1.27)
			)
			(justify left bottom)
		)
	)
	(label "ETH.TXC"
		(at 92.71 166.37 0)
		(effects
			(font
				(size 1.27 1.27)
			)
			(justify left bottom)
		)
	)
	(label "ETH.MDIO"
		(at 87.63 149.86 180)
		(effects
			(font
				(size 1.27 1.27)
			)
			(justify right bottom)
		)
	)
	(label "LED_SPD"
		(at 361.95 81.28 180)
		(effects
			(font
				(size 1.27 1.27)
			)
			(justify right bottom)
		)
	)
	(label "ETH.TXD1"
		(at 92.71 158.75 0)
		(effects
			(font
				(size 1.27 1.27)
			)
			(justify left bottom)
		)
	)
	(label "ETH.MDIO"
		(at 92.71 149.86 0)
		(effects
			(font
				(size 1.27 1.27)
			)
			(justify left bottom)
		)
	)
	(label "ETH.RXD2"
		(at 336.55 163.83 180)
		(effects
			(font
				(size 1.27 1.27)
			)
			(justify right bottom)
		)
	)
	(label "ETH.TXD2"
		(at 92.71 161.29 0)
		(effects
			(font
				(size 1.27 1.27)
			)
			(justify left bottom)
		)
	)
	(label "AVDDL"
		(at 161.29 137.16 180)
		(effects
			(font
				(size 1.27 1.27)
			)
			(justify right bottom)
		)
	)
	(label "ETH.RXD3"
		(at 92.71 180.34 0)
		(effects
			(font
				(size 1.27 1.27)
			)
			(justify left bottom)
		)
	)
	(label "ETH.MDC"
		(at 92.71 147.32 0)
		(effects
			(font
				(size 1.27 1.27)
			)
			(justify left bottom)
		)
	)
	(label "ETH.RXD0"
		(at 336.55 168.91 180)
		(effects
			(font
				(size 1.27 1.27)
			)
			(justify right bottom)
		)
	)
	(label "ETH.TXD3"
		(at 92.71 163.83 0)
		(effects
			(font
				(size 1.27 1.27)
			)
			(justify left bottom)
		)
	)
	(label "LED_SPD"
		(at 163.83 177.8 180)
		(effects
			(font
				(size 1.27 1.27)
			)
			(justify right bottom)
		)
	)
	(label "ETH2_N"
		(at 307.34 60.96 0)
		(effects
			(font
				(size 1.27 1.27)
			)
			(justify left bottom)
		)
	)
	(label "ETH.TX_CTL"
		(at 92.71 153.67 0)
		(effects
			(font
				(size 1.27 1.27)
			)
			(justify left bottom)
		)
	)
	(label "AVDDL_PLL"
		(at 165.1 139.7 180)
		(effects
			(font
				(size 1.27 1.27)
			)
			(justify right bottom)
		)
	)
	(label "ETH.RXD3"
		(at 336.55 161.29 180)
		(effects
			(font
				(size 1.27 1.27)
			)
			(justify right bottom)
		)
	)
	(label "ETH.RXD2"
		(at 92.71 177.8 0)
		(effects
			(font
				(size 1.27 1.27)
			)
			(justify left bottom)
		)
	)
	(label "ETH.RXD1"
		(at 92.71 175.26 0)
		(effects
			(font
				(size 1.27 1.27)
			)
			(justify left bottom)
		)
	)
	(label "ETH.RXD0"
		(at 92.71 172.72 0)
		(effects
			(font
				(size 1.27 1.27)
			)
			(justify left bottom)
		)
	)
	(label "ETH.REF_CLK"
		(at 92.71 186.69 0)
		(effects
			(font
				(size 1.27 1.27)
			)
			(justify left bottom)
		)
	)
	(label "ETH.~{RESET}"
		(at 87.63 140.97 180)
		(effects
			(font
				(size 1.27 1.27)
			)
			(justify right bottom)
		)
	)
	(label "ETH4_P"
		(at 166.37 166.37 180)
		(effects
			(font
				(size 1.27 1.27)
			)
			(justify right bottom)
		)
	)
	(label "ETH.~{INT}"
		(at 92.71 143.51 0)
		(effects
			(font
				(size 1.27 1.27)
			)
			(justify left bottom)
		)
	)
	(label "ETH.REF_CLK"
		(at 336.55 182.88 180)
		(effects
			(font
				(size 1.27 1.27)
			)
			(justify right bottom)
		)
	)
	(label "LED_LINK"
		(at 163.83 175.26 180)
		(effects
			(font
				(size 1.27 1.27)
			)
			(justify right bottom)
		)
	)
	(label "LED_SPD"
		(at 336.55 173.99 180)
		(effects
			(font
				(size 1.27 1.27)
			)
			(justify right bottom)
		)
	)
	(label "ETH.RX_CTL"
		(at 336.55 180.34 180)
		(effects
			(font
				(size 1.27 1.27)
			)
			(justify right bottom)
		)
	)
	(hierarchical_label "ETH{RGMII}"
		(shape bidirectional)
		(at 86.36 135.89 180)
		(effects
			(font
				(size 1.27 1.27)
			)
			(justify right)
		)
	)
	(symbol
		(lib_id "antmicroResistors0402:R_1M8_0402")
		(at 96.52 193.04 0)
		(mirror y)
		(unit 1)
		(exclude_from_sim no)
		(in_bom yes)
		(on_board yes)
		(dnp no)
		(property "Reference" "R100"
			(at 89.535 191.77 0)
			(effects
				(font
					(size 1.27 1.27)
				)
			)
		)
		(property "Value" "R_1M8_0402"
			(at 76.2 205.74 0)
			(effects
				(font
					(size 1.27 1.27)
					(thickness 0.15)
				)
				(justify left bottom)
				(hide yes)
			)
		)
		(property "Footprint" "antmicro-footprints:R_0402_1005Metric"
			(at 76.2 208.28 0)
			(effects
				(font
					(size 1.27 1.27)
					(thickness 0.15)
				)
				(justify left bottom)
				(hide yes)
			)
		)
		(property "Datasheet" "https://www.bourns.com/docs/product-datasheets/cr.pdf"
			(at 76.2 210.82 0)
			(effects
				(font
					(size 1.27 1.27)
					(thickness 0.15)
				)
				(justify left bottom)
				(hide yes)
			)
		)
		(property "Description" ""
			(at 96.52 193.04 0)
			(effects
				(font
					(size 1.27 1.27)
				)
				(hide yes)
			)
		)
		(property "Manufacturer" "Bourns"
			(at 76.2 215.9 0)
			(effects
				(font
					(size 1.27 1.27)
					(thickness 0.15)
				)
				(justify left bottom)
				(hide yes)
			)
		)
		(property "MPN" "CR0402-FX-1804GLF"
			(at 76.2 213.36 0)
			(effects
				(font
					(size 1.27 1.27)
					(thickness 0.15)
				)
				(justify left bottom)
				(hide yes)
			)
		)
		(property "Val" "1M8"
			(at 98.425 191.77 0)
			(effects
				(font
					(size 1.27 1.27)
					(thickness 0.15)
				)
			)
		)
		(property "License" "Apache-2.0"
			(at 76.2 218.44 0)
			(effects
				(font
					(size 1.27 1.27)
					(thickness 0.15)
				)
				(justify left bottom)
				(hide yes)
			)
		)
		(property "Author" "Antmicro"
			(at 76.2 220.98 0)
			(effects
				(font
					(size 1.27 1.27)
					(thickness 0.15)
				)
				(justify left bottom)
				(hide yes)
			)
		)
		(property "Tolerance" "1%"
			(at 76.2 203.2 0)
			(effects
				(font
					(size 1.27 1.27)
				)
				(justify left bottom)
				(hide yes)
			)
		)
		(pin "1"
		)
		(pin "2"
		)
		(instances
			(project "data-center-rdimm-ddr5-tester"
				(path ""
					(reference "R100")
					(unit 1)
				)
			)
		)
	)
	(symbol
		(lib_id "antmicroInterfaceControllers:KSZ9031RNXCA")
		(at 109.22 133.35 0)
		(unit 1)
		(exclude_from_sim no)
		(in_bom yes)
		(on_board yes)
		(dnp no)
		(property "Reference" "U15"
			(at 131.445 125.73 0)
			(effects
				(font
					(size 1.27 1.27)
				)
			)
		)
		(property "Value" "KSZ9031RNXCA"
			(at 131.445 128.27 0)
			(effects
				(font
					(size 1.27 1.27)
					(thickness 0.15)
				)
				(hide yes)
			)
		)
		(property "Footprint" "antmicro-footprints:QFN-48-1EP_7x7x0.9mm_P0.5mm_EP3.5x3.5mm"
			(at 185.42 143.51 0)
			(effects
				(font
					(size 1.27 1.27)
					(thickness 0.15)
				)
				(justify left bottom)
				(hide yes)
			)
		)
		(property "Datasheet" "http://ww1.microchip.com/downloads/en/DeviceDoc/00002117F.pdf"
			(at 185.42 146.05 0)
			(effects
				(font
					(size 1.27 1.27)
					(thickness 0.15)
				)
				(justify left bottom)
				(hide yes)
			)
		)
		(property "Description" ""
			(at 109.22 133.35 0)
			(effects
				(font
					(size 1.27 1.27)
				)
				(hide yes)
			)
		)
		(property "Manufacturer" "Microchip Technology"
			(at 185.42 148.59 0)
			(effects
				(font
					(size 1.27 1.27)
					(thickness 0.15)
				)
				(justify left bottom)
				(hide yes)
			)
		)
		(property "MPN" "KSZ9031RNXCA"
			(at 123.825 129.54 0)
			(effects
				(font
					(size 1.27 1.27)
					(thickness 0.15)
				)
				(justify left bottom)
			)
		)
		(property "Author" "Antmicro"
			(at 185.42 153.67 0)
			(effects
				(font
					(size 1.27 1.27)
					(thickness 0.15)
				)
				(justify left bottom)
				(hide yes)
			)
		)
		(property "License" "Apache-2.0"
			(at 185.42 156.21 0)
			(effects
				(font
					(size 1.27 1.27)
					(thickness 0.15)
				)
				(justify left bottom)
				(hide yes)
			)
		)
		(pin "1"
		)
		(pin "10"
		)
		(pin "11"
		)
		(pin "12"
		)
		(pin "13"
		)
		(pin "14"
		)
		(pin "15"
		)
		(pin "16"
		)
		(pin "17"
		)
		(pin "18"
		)
		(pin "19"
		)
		(pin "2"
		)
		(pin "20"
		)
		(pin "21"
		)
		(pin "22"
		)
		(pin "23"
		)
		(pin "24"
		)
		(pin "25"
		)
		(pin "26"
		)
		(pin "27"
		)
		(pin "28"
		)
		(pin "29"
		)
		(pin "3"
		)
		(pin "30"
		)
		(pin "31"
		)
		(pin "32"
		)
		(pin "33"
		)
		(pin "34"
		)
		(pin "35"
		)
		(pin "36"
		)
		(pin "37"
		)
		(pin "38"
		)
		(pin "39"
		)
		(pin "4"
		)
		(pin "40"
		)
		(pin "41"
		)
		(pin "42"
		)
		(pin "43"
		)
		(pin "44"
		)
		(pin "45"
		)
		(pin "46"
		)
		(pin "47"
		)
		(pin "48"
		)
		(pin "49"
		)
		(pin "5"
		)
		(pin "6"
		)
		(pin "7"
		)
		(pin "8"
		)
		(pin "9"
		)
		(instances
			(project "data-center-rdimm-ddr5-tester"
				(path ""
					(reference "U15")
					(unit 1)
				)
			)
		)
	)
	(symbol
		(lib_id "antmicroResistors0402:R_12k1_0402")
		(at 156.21 189.23 90)
		(unit 1)
		(exclude_from_sim no)
		(in_bom yes)
		(on_board yes)
		(dnp no)
		(fields_autoplaced yes)
		(property "Reference" "R112"
			(at 158.75 185.42 90)
			(effects
				(font
					(size 1.27 1.27)
				)
				(justify right)
			)
		)
		(property "Value" "R_12k1_0402"
			(at 168.91 168.91 0)
			(effects
				(font
					(size 1.27 1.27)
					(thickness 0.15)
				)
				(justify left bottom)
				(hide yes)
			)
		)
		(property "Footprint" "antmicro-footprints:R_0402_1005Metric"
			(at 171.45 168.91 0)
			(effects
				(font
					(size 1.27 1.27)
					(thickness 0.15)
				)
				(justify left bottom)
				(hide yes)
			)
		)
		(property "Datasheet" "https://www.bourns.com/docs/product-datasheets/cr.pdf"
			(at 173.99 168.91 0)
			(effects
				(font
					(size 1.27 1.27)
					(thickness 0.15)
				)
				(justify left bottom)
				(hide yes)
			)
		)
		(property "Description" ""
			(at 156.21 189.23 0)
			(effects
				(font
					(size 1.27 1.27)
				)
				(hide yes)
			)
		)
		(property "Manufacturer" "Bourns"
			(at 179.07 168.91 0)
			(effects
				(font
					(size 1.27 1.27)
					(thickness 0.15)
				)
				(justify left bottom)
				(hide yes)
			)
		)
		(property "MPN" "CR0402-FX-1212GLF"
			(at 176.53 168.91 0)
			(effects
				(font
					(size 1.27 1.27)
					(thickness 0.15)
				)
				(justify left bottom)
				(hide yes)
			)
		)
		(property "Val" "12k1"
			(at 158.75 188.5949 90)
			(effects
				(font
					(size 1.27 1.27)
					(thickness 0.15)
				)
				(justify right)
			)
		)
		(property "License" "Apache-2.0"
			(at 181.61 168.91 0)
			(effects
				(font
					(size 1.27 1.27)
					(thickness 0.15)
				)
				(justify left bottom)
				(hide yes)
			)
		)
		(property "Author" "Antmicro"
			(at 184.15 168.91 0)
			(effects
				(font
					(size 1.27 1.27)
					(thickness 0.15)
				)
				(justify left bottom)
				(hide yes)
			)
		)
		(property "Tolerance" "1%"
			(at 166.37 168.91 0)
			(effects
				(font
					(size 1.27 1.27)
				)
				(justify left bottom)
				(hide yes)
			)
		)
		(pin "1"
		)
		(pin "2"
		)
		(instances
			(project "data-center-rdimm-ddr5-tester"
				(path ""
					(reference "R112")
					(unit 1)
				)
			)
		)
	)
	(symbol
		(lib_id "antmicropower:GND")
		(at 156.21 195.58 0)
		(unit 1)
		(exclude_from_sim no)
		(in_bom yes)
		(on_board yes)
		(dnp no)
		(fields_autoplaced yes)
		(property "Reference" "#PWR0259"
			(at 156.21 201.93 0)
			(effects
				(font
					(size 1.27 1.27)
				)
				(hide yes)
			)
		)
		(property "Value" "GND"
			(at 154.305 200.025 0)
			(effects
				(font
					(size 1.27 1.27)
					(thickness 0.15)
				)
				(justify left bottom)
			)
		)
		(property "Footprint" ""
			(at 165.1 203.2 0)
			(effects
				(font
					(size 1.27 1.27)
					(thickness 0.15)
				)
				(justify left bottom)
				(hide yes)
			)
		)
		(property "Datasheet" ""
			(at 165.1 208.28 0)
			(effects
				(font
					(size 1.27 1.27)
					(thickness 0.15)
				)
				(justify left bottom)
				(hide yes)
			)
		)
		(property "Description" ""
			(at 156.21 195.58 0)
			(effects
				(font
					(size 1.27 1.27)
				)
				(hide yes)
			)
		)
		(property "Author" "Antmicro"
			(at 165.1 200.66 0)
			(effects
				(font
					(size 1.27 1.27)
					(thickness 0.15)
				)
				(justify left bottom)
				(hide yes)
			)
		)
		(property "License" "Apache-2.0"
			(at 165.1 203.2 0)
			(effects
				(font
					(size 1.27 1.27)
					(thickness 0.15)
				)
				(justify left bottom)
				(hide yes)
			)
		)
		(pin "1"
		)
		(instances
			(project "data-center-rdimm-ddr5-tester"
				(path ""
					(reference "#PWR0259")
					(unit 1)
				)
			)
		)
	)
	(symbol
		(lib_id "antmicropower:GND")
		(at 93.98 212.09 0)
		(mirror y)
		(unit 1)
		(exclude_from_sim no)
		(in_bom yes)
		(on_board yes)
		(dnp no)
		(fields_autoplaced yes)
		(property "Reference" "#PWR0256"
			(at 93.98 218.44 0)
			(effects
				(font
					(size 1.27 1.27)
				)
				(hide yes)
			)
		)
		(property "Value" "GND"
			(at 95.885 216.535 0)
			(effects
				(font
					(size 1.27 1.27)
					(thickness 0.15)
				)
				(justify left bottom)
			)
		)
		(property "Footprint" ""
			(at 85.09 219.71 0)
			(effects
				(font
					(size 1.27 1.27)
					(thickness 0.15)
				)
				(justify left bottom)
				(hide yes)
			)
		)
		(property "Datasheet" ""
			(at 85.09 224.79 0)
			(effects
				(font
					(size 1.27 1.27)
					(thickness 0.15)
				)
				(justify left bottom)
				(hide yes)
			)
		)
		(property "Description" ""
			(at 93.98 212.09 0)
			(effects
				(font
					(size 1.27 1.27)
				)
				(hide yes)
			)
		)
		(property "Author" "Antmicro"
			(at 85.09 217.17 0)
			(effects
				(font
					(size 1.27 1.27)
					(thickness 0.15)
				)
				(justify left bottom)
				(hide yes)
			)
		)
		(property "License" "Apache-2.0"
			(at 85.09 219.71 0)
			(effects
				(font
					(size 1.27 1.27)
					(thickness 0.15)
				)
				(justify left bottom)
				(hide yes)
			)
		)
		(pin "1"
		)
		(instances
			(project "data-center-rdimm-ddr5-tester"
				(path ""
					(reference "#PWR0256")
					(unit 1)
				)
			)
		)
	)
	(symbol
		(lib_id "antmicroCapacitors0402:C_4u7_0402")
		(at 199.39 128.27 90)
		(mirror x)
		(unit 1)
		(exclude_from_sim no)
		(in_bom yes)
		(on_board yes)
		(dnp no)
		(property "Reference" "C146"
			(at 200.025 128.905 90)
			(effects
				(font
					(size 1.27 1.27)
				)
				(justify right)
			)
		)
		(property "Value" "C_4u7_0402"
			(at 209.55 148.59 0)
			(effects
				(font
					(size 1.27 1.27)
					(thickness 0.15)
				)
				(justify left bottom)
				(hide yes)
			)
		)
		(property "Footprint" "antmicro-footprints:C_0402_1005Metric"
			(at 212.09 148.59 0)
			(effects
				(font
					(size 1.27 1.27)
					(thickness 0.15)
				)
				(justify left bottom)
				(hide yes)
			)
		)
		(property "Datasheet" "https://www.murata.com/products/productdetail?partno=GRM155R61A475MEAA%23"
			(at 214.63 148.59 0)
			(effects
				(font
					(size 1.27 1.27)
					(thickness 0.15)
				)
				(justify left bottom)
				(hide yes)
			)
		)
		(property "Description" ""
			(at 199.39 128.27 0)
			(effects
				(font
					(size 1.27 1.27)
				)
				(hide yes)
			)
		)
		(property "Manufacturer" "Murata"
			(at 219.71 148.59 0)
			(effects
				(font
					(size 1.27 1.27)
					(thickness 0.15)
				)
				(justify left bottom)
				(hide yes)
			)
		)
		(property "MPN" "GRM155R61A475MEAAD"
			(at 217.17 148.59 0)
			(effects
				(font
					(size 1.27 1.27)
					(thickness 0.15)
				)
				(justify left bottom)
				(hide yes)
			)
		)
		(property "Val" "4u7"
			(at 200.025 132.715 90)
			(effects
				(font
					(size 1.27 1.27)
					(thickness 0.15)
				)
				(justify right)
			)
		)
		(property "License" "Apache-2.0"
			(at 222.25 148.59 0)
			(effects
				(font
					(size 1.27 1.27)
					(thickness 0.15)
				)
				(justify left bottom)
				(hide yes)
			)
		)
		(property "Author" "Antmicro"
			(at 224.79 148.59 0)
			(effects
				(font
					(size 1.27 1.27)
					(thickness 0.15)
				)
				(justify left bottom)
				(hide yes)
			)
		)
		(property "Voltage" ""
			(at 227.33 148.59 0)
			(effects
				(font
					(size 1.27 1.27)
				)
				(justify left bottom)
				(hide yes)
			)
		)
		(property "Dielectric" ""
			(at 229.87 148.59 0)
			(effects
				(font
					(size 1.27 1.27)
				)
				(justify left bottom)
				(hide yes)
			)
		)
		(pin "1"
		)
		(pin "2"
		)
		(instances
			(project "data-center-rdimm-ddr5-tester"
				(path ""
					(reference "C146")
					(unit 1)
				)
			)
		)
	)
	(symbol
		(lib_id "antmicroCapacitors0402:C_470n_0402")
		(at 191.77 128.27 90)
		(mirror x)
		(unit 1)
		(exclude_from_sim no)
		(in_bom yes)
		(on_board yes)
		(dnp no)
		(property "Reference" "C143"
			(at 192.405 128.905 90)
			(effects
				(font
					(size 1.27 1.27)
				)
				(justify right)
			)
		)
		(property "Value" "C_470n_0402"
			(at 201.93 148.59 0)
			(effects
				(font
					(size 1.27 1.27)
					(thickness 0.15)
				)
				(justify left bottom)
				(hide yes)
			)
		)
		(property "Footprint" "antmicro-footprints:C_0402_1005Metric"
			(at 204.47 148.59 0)
			(effects
				(font
					(size 1.27 1.27)
					(thickness 0.15)
				)
				(justify left bottom)
				(hide yes)
			)
		)
		(property "Datasheet" "https://product.tdk.com/en/search/capacitor/ceramic/mlcc/info?part_no=C1005X5R1E474M050BB"
			(at 207.01 148.59 0)
			(effects
				(font
					(size 1.27 1.27)
					(thickness 0.15)
				)
				(justify left bottom)
				(hide yes)
			)
		)
		(property "Description" ""
			(at 191.77 128.27 0)
			(effects
				(font
					(size 1.27 1.27)
				)
				(hide yes)
			)
		)
		(property "Manufacturer" "TDK"
			(at 212.09 148.59 0)
			(effects
				(font
					(size 1.27 1.27)
					(thickness 0.15)
				)
				(justify left bottom)
				(hide yes)
			)
		)
		(property "MPN" "C1005X5R1E474M050BB"
			(at 209.55 148.59 0)
			(effects
				(font
					(size 1.27 1.27)
					(thickness 0.15)
				)
				(justify left bottom)
				(hide yes)
			)
		)
		(property "Val" "470n"
			(at 192.405 132.715 90)
			(effects
				(font
					(size 1.27 1.27)
					(thickness 0.15)
				)
				(justify right)
			)
		)
		(property "License" "Apache-2.0"
			(at 214.63 148.59 0)
			(effects
				(font
					(size 1.27 1.27)
					(thickness 0.15)
				)
				(justify left bottom)
				(hide yes)
			)
		)
		(property "Author" "Antmicro"
			(at 217.17 148.59 0)
			(effects
				(font
					(size 1.27 1.27)
					(thickness 0.15)
				)
				(justify left bottom)
				(hide yes)
			)
		)
		(property "Voltage" ""
			(at 219.71 148.59 0)
			(effects
				(font
					(size 1.27 1.27)
				)
				(justify left bottom)
				(hide yes)
			)
		)
		(property "Dielectric" ""
			(at 222.25 148.59 0)
			(effects
				(font
					(size 1.27 1.27)
				)
				(justify left bottom)
				(hide yes)
			)
		)
		(pin "1"
		)
		(pin "2"
		)
		(instances
			(project "data-center-rdimm-ddr5-tester"
				(path ""
					(reference "C143")
					(unit 1)
				)
			)
		)
	)
	(symbol
		(lib_id "antmicroCapacitors0402:C_10n_0402")
		(at 182.88 128.27 90)
		(mirror x)
		(unit 1)
		(exclude_from_sim no)
		(in_bom yes)
		(on_board yes)
		(dnp no)
		(property "Reference" "C140"
			(at 183.515 128.905 90)
			(effects
				(font
					(size 1.27 1.27)
				)
				(justify right)
			)
		)
		(property "Value" "C_10n_0402"
			(at 193.04 148.59 0)
			(effects
				(font
					(size 1.27 1.27)
					(thickness 0.15)
				)
				(justify left bottom)
				(hide yes)
			)
		)
		(property "Footprint" "antmicro-footprints:C_0402_1005Metric"
			(at 195.58 148.59 0)
			(effects
				(font
					(size 1.27 1.27)
					(thickness 0.15)
				)
				(justify left bottom)
				(hide yes)
			)
		)
		(property "Datasheet" "https://www.murata.com/products/productdetail?partno=GRM155R71H103KA88%23"
			(at 198.12 148.59 0)
			(effects
				(font
					(size 1.27 1.27)
					(thickness 0.15)
				)
				(justify left bottom)
				(hide yes)
			)
		)
		(property "Description" ""
			(at 182.88 128.27 0)
			(effects
				(font
					(size 1.27 1.27)
				)
				(hide yes)
			)
		)
		(property "Manufacturer" "Murata"
			(at 203.2 148.59 0)
			(effects
				(font
					(size 1.27 1.27)
					(thickness 0.15)
				)
				(justify left bottom)
				(hide yes)
			)
		)
		(property "MPN" "GRM155R71H103KA88D"
			(at 200.66 148.59 0)
			(effects
				(font
					(size 1.27 1.27)
					(thickness 0.15)
				)
				(justify left bottom)
				(hide yes)
			)
		)
		(property "Val" "10n"
			(at 183.515 132.715 90)
			(effects
				(font
					(size 1.27 1.27)
					(thickness 0.15)
				)
				(justify right)
			)
		)
		(property "License" "Apache-2.0"
			(at 205.74 148.59 0)
			(effects
				(font
					(size 1.27 1.27)
					(thickness 0.15)
				)
				(justify left bottom)
				(hide yes)
			)
		)
		(property "Author" "Antmicro"
			(at 208.28 148.59 0)
			(effects
				(font
					(size 1.27 1.27)
					(thickness 0.15)
				)
				(justify left bottom)
				(hide yes)
			)
		)
		(property "Voltage" "50V"
			(at 210.82 148.59 0)
			(effects
				(font
					(size 1.27 1.27)
				)
				(justify left bottom)
				(hide yes)
			)
		)
		(property "Dielectric" "X7R"
			(at 213.36 148.59 0)
			(effects
				(font
					(size 1.27 1.27)
				)
				(justify left bottom)
				(hide yes)
			)
		)
		(pin "1"
		)
		(pin "2"
		)
		(instances
			(project "data-center-rdimm-ddr5-tester"
				(path ""
					(reference "C140")
					(unit 1)
				)
			)
		)
	)
	(symbol
		(lib_id "antmicroCapacitors0402:C_10n_0402")
		(at 175.26 128.27 90)
		(mirror x)
		(unit 1)
		(exclude_from_sim no)
		(in_bom yes)
		(on_board yes)
		(dnp no)
		(property "Reference" "C136"
			(at 175.895 128.905 90)
			(effects
				(font
					(size 1.27 1.27)
				)
				(justify right)
			)
		)
		(property "Value" "C_10n_0402"
			(at 185.42 148.59 0)
			(effects
				(font
					(size 1.27 1.27)
					(thickness 0.15)
				)
				(justify left bottom)
				(hide yes)
			)
		)
		(property "Footprint" "antmicro-footprints:C_0402_1005Metric"
			(at 187.96 148.59 0)
			(effects
				(font
					(size 1.27 1.27)
					(thickness 0.15)
				)
				(justify left bottom)
				(hide yes)
			)
		)
		(property "Datasheet" "https://www.murata.com/products/productdetail?partno=GRM155R71H103KA88%23"
			(at 190.5 148.59 0)
			(effects
				(font
					(size 1.27 1.27)
					(thickness 0.15)
				)
				(justify left bottom)
				(hide yes)
			)
		)
		(property "Description" ""
			(at 175.26 128.27 0)
			(effects
				(font
					(size 1.27 1.27)
				)
				(hide yes)
			)
		)
		(property "Manufacturer" "Murata"
			(at 195.58 148.59 0)
			(effects
				(font
					(size 1.27 1.27)
					(thickness 0.15)
				)
				(justify left bottom)
				(hide yes)
			)
		)
		(property "MPN" "GRM155R71H103KA88D"
			(at 193.04 148.59 0)
			(effects
				(font
					(size 1.27 1.27)
					(thickness 0.15)
				)
				(justify left bottom)
				(hide yes)
			)
		)
		(property "Val" "10n"
			(at 175.895 132.715 90)
			(effects
				(font
					(size 1.27 1.27)
					(thickness 0.15)
				)
				(justify right)
			)
		)
		(property "License" "Apache-2.0"
			(at 198.12 148.59 0)
			(effects
				(font
					(size 1.27 1.27)
					(thickness 0.15)
				)
				(justify left bottom)
				(hide yes)
			)
		)
		(property "Author" "Antmicro"
			(at 200.66 148.59 0)
			(effects
				(font
					(size 1.27 1.27)
					(thickness 0.15)
				)
				(justify left bottom)
				(hide yes)
			)
		)
		(property "Voltage" "50V"
			(at 203.2 148.59 0)
			(effects
				(font
					(size 1.27 1.27)
				)
				(justify left bottom)
				(hide yes)
			)
		)
		(property "Dielectric" "X7R"
			(at 205.74 148.59 0)
			(effects
				(font
					(size 1.27 1.27)
				)
				(justify left bottom)
				(hide yes)
			)
		)
		(pin "1"
		)
		(pin "2"
		)
		(instances
			(project "data-center-rdimm-ddr5-tester"
				(path ""
					(reference "C136")
					(unit 1)
				)
			)
		)
	)
	(symbol
		(lib_id "antmicroCapacitors0402:C_10n_0402")
		(at 182.88 107.95 90)
		(mirror x)
		(unit 1)
		(exclude_from_sim no)
		(in_bom yes)
		(on_board yes)
		(dnp no)
		(property "Reference" "C153"
			(at 182.245 108.585 90)
			(effects
				(font
					(size 1.27 1.27)
				)
				(justify left)
			)
		)
		(property "Value" "C_10n_0402"
			(at 193.04 128.27 0)
			(effects
				(font
					(size 1.27 1.27)
					(thickness 0.15)
				)
				(justify left bottom)
				(hide yes)
			)
		)
		(property "Footprint" "antmicro-footprints:C_0402_1005Metric"
			(at 195.58 128.27 0)
			(effects
				(font
					(size 1.27 1.27)
					(thickness 0.15)
				)
				(justify left bottom)
				(hide yes)
			)
		)
		(property "Datasheet" "https://www.murata.com/products/productdetail?partno=GRM155R71H103KA88%23"
			(at 198.12 128.27 0)
			(effects
				(font
					(size 1.27 1.27)
					(thickness 0.15)
				)
				(justify left bottom)
				(hide yes)
			)
		)
		(property "Description" ""
			(at 182.88 107.95 0)
			(effects
				(font
					(size 1.27 1.27)
				)
				(hide yes)
			)
		)
		(property "Manufacturer" "Murata"
			(at 203.2 128.27 0)
			(effects
				(font
					(size 1.27 1.27)
					(thickness 0.15)
				)
				(justify left bottom)
				(hide yes)
			)
		)
		(property "MPN" "GRM155R71H103KA88D"
			(at 200.66 128.27 0)
			(effects
				(font
					(size 1.27 1.27)
					(thickness 0.15)
				)
				(justify left bottom)
				(hide yes)
			)
		)
		(property "Val" "10n"
			(at 182.245 112.395 90)
			(effects
				(font
					(size 1.27 1.27)
					(thickness 0.15)
				)
				(justify left)
			)
		)
		(property "License" "Apache-2.0"
			(at 205.74 128.27 0)
			(effects
				(font
					(size 1.27 1.27)
					(thickness 0.15)
				)
				(justify left bottom)
				(hide yes)
			)
		)
		(property "Author" "Antmicro"
			(at 208.28 128.27 0)
			(effects
				(font
					(size 1.27 1.27)
					(thickness 0.15)
				)
				(justify left bottom)
				(hide yes)
			)
		)
		(property "Voltage" "50V"
			(at 210.82 128.27 0)
			(effects
				(font
					(size 1.27 1.27)
				)
				(justify left bottom)
				(hide yes)
			)
		)
		(property "Dielectric" "X7R"
			(at 213.36 128.27 0)
			(effects
				(font
					(size 1.27 1.27)
				)
				(justify left bottom)
				(hide yes)
			)
		)
		(pin "1"
		)
		(pin "2"
		)
		(instances
			(project "data-center-rdimm-ddr5-tester"
				(path ""
					(reference "C153")
					(unit 1)
				)
			)
		)
	)
	(symbol
		(lib_id "antmicroCapacitors0402:C_10n_0402")
		(at 175.26 107.95 90)
		(mirror x)
		(unit 1)
		(exclude_from_sim no)
		(in_bom yes)
		(on_board yes)
		(dnp no)
		(property "Reference" "C156"
			(at 174.625 108.585 90)
			(effects
				(font
					(size 1.27 1.27)
				)
				(justify left)
			)
		)
		(property "Value" "C_10n_0402"
			(at 185.42 128.27 0)
			(effects
				(font
					(size 1.27 1.27)
					(thickness 0.15)
				)
				(justify left bottom)
				(hide yes)
			)
		)
		(property "Footprint" "antmicro-footprints:C_0402_1005Metric"
			(at 187.96 128.27 0)
			(effects
				(font
					(size 1.27 1.27)
					(thickness 0.15)
				)
				(justify left bottom)
				(hide yes)
			)
		)
		(property "Datasheet" "https://www.murata.com/products/productdetail?partno=GRM155R71H103KA88%23"
			(at 190.5 128.27 0)
			(effects
				(font
					(size 1.27 1.27)
					(thickness 0.15)
				)
				(justify left bottom)
				(hide yes)
			)
		)
		(property "Description" ""
			(at 175.26 107.95 0)
			(effects
				(font
					(size 1.27 1.27)
				)
				(hide yes)
			)
		)
		(property "Manufacturer" "Murata"
			(at 195.58 128.27 0)
			(effects
				(font
					(size 1.27 1.27)
					(thickness 0.15)
				)
				(justify left bottom)
				(hide yes)
			)
		)
		(property "MPN" "GRM155R71H103KA88D"
			(at 193.04 128.27 0)
			(effects
				(font
					(size 1.27 1.27)
					(thickness 0.15)
				)
				(justify left bottom)
				(hide yes)
			)
		)
		(property "Val" "10n"
			(at 174.625 112.395 90)
			(effects
				(font
					(size 1.27 1.27)
					(thickness 0.15)
				)
				(justify left)
			)
		)
		(property "License" "Apache-2.0"
			(at 198.12 128.27 0)
			(effects
				(font
					(size 1.27 1.27)
					(thickness 0.15)
				)
				(justify left bottom)
				(hide yes)
			)
		)
		(property "Author" "Antmicro"
			(at 200.66 128.27 0)
			(effects
				(font
					(size 1.27 1.27)
					(thickness 0.15)
				)
				(justify left bottom)
				(hide yes)
			)
		)
		(property "Voltage" "50V"
			(at 203.2 128.27 0)
			(effects
				(font
					(size 1.27 1.27)
				)
				(justify left bottom)
				(hide yes)
			)
		)
		(property "Dielectric" "X7R"
			(at 205.74 128.27 0)
			(effects
				(font
					(size 1.27 1.27)
				)
				(justify left bottom)
				(hide yes)
			)
		)
		(pin "1"
		)
		(pin "2"
		)
		(instances
			(project "data-center-rdimm-ddr5-tester"
				(path ""
					(reference "C156")
					(unit 1)
				)
			)
		)
	)
	(symbol
		(lib_id "antmicroCapacitors0402:C_10n_0402")
		(at 199.39 107.95 90)
		(mirror x)
		(unit 1)
		(exclude_from_sim no)
		(in_bom yes)
		(on_board yes)
		(dnp no)
		(property "Reference" "C150"
			(at 198.755 108.585 90)
			(effects
				(font
					(size 1.27 1.27)
				)
				(justify left)
			)
		)
		(property "Value" "C_10n_0402"
			(at 209.55 128.27 0)
			(effects
				(font
					(size 1.27 1.27)
					(thickness 0.15)
				)
				(justify left bottom)
				(hide yes)
			)
		)
		(property "Footprint" "antmicro-footprints:C_0402_1005Metric"
			(at 212.09 128.27 0)
			(effects
				(font
					(size 1.27 1.27)
					(thickness 0.15)
				)
				(justify left bottom)
				(hide yes)
			)
		)
		(property "Datasheet" "https://www.murata.com/products/productdetail?partno=GRM155R71H103KA88%23"
			(at 214.63 128.27 0)
			(effects
				(font
					(size 1.27 1.27)
					(thickness 0.15)
				)
				(justify left bottom)
				(hide yes)
			)
		)
		(property "Description" ""
			(at 199.39 107.95 0)
			(effects
				(font
					(size 1.27 1.27)
				)
				(hide yes)
			)
		)
		(property "Manufacturer" "Murata"
			(at 219.71 128.27 0)
			(effects
				(font
					(size 1.27 1.27)
					(thickness 0.15)
				)
				(justify left bottom)
				(hide yes)
			)
		)
		(property "MPN" "GRM155R71H103KA88D"
			(at 217.17 128.27 0)
			(effects
				(font
					(size 1.27 1.27)
					(thickness 0.15)
				)
				(justify left bottom)
				(hide yes)
			)
		)
		(property "Val" "10n"
			(at 198.755 112.395 90)
			(effects
				(font
					(size 1.27 1.27)
					(thickness 0.15)
				)
				(justify left)
			)
		)
		(property "License" "Apache-2.0"
			(at 222.25 128.27 0)
			(effects
				(font
					(size 1.27 1.27)
					(thickness 0.15)
				)
				(justify left bottom)
				(hide yes)
			)
		)
		(property "Author" "Antmicro"
			(at 224.79 128.27 0)
			(effects
				(font
					(size 1.27 1.27)
					(thickness 0.15)
				)
				(justify left bottom)
				(hide yes)
			)
		)
		(property "Voltage" "50V"
			(at 227.33 128.27 0)
			(effects
				(font
					(size 1.27 1.27)
				)
				(justify left bottom)
				(hide yes)
			)
		)
		(property "Dielectric" "X7R"
			(at 229.87 128.27 0)
			(effects
				(font
					(size 1.27 1.27)
				)
				(justify left bottom)
				(hide yes)
			)
		)
		(pin "1"
		)
		(pin "2"
		)
		(instances
			(project "data-center-rdimm-ddr5-tester"
				(path ""
					(reference "C150")
					(unit 1)
				)
			)
		)
	)
	(symbol
		(lib_id "antmicroCapacitors0402:C_10n_0402")
		(at 191.77 107.95 90)
		(mirror x)
		(unit 1)
		(exclude_from_sim no)
		(in_bom yes)
		(on_board yes)
		(dnp no)
		(property "Reference" "C151"
			(at 191.135 108.585 90)
			(effects
				(font
					(size 1.27 1.27)
				)
				(justify left)
			)
		)
		(property "Value" "C_10n_0402"
			(at 201.93 128.27 0)
			(effects
				(font
					(size 1.27 1.27)
					(thickness 0.15)
				)
				(justify left bottom)
				(hide yes)
			)
		)
		(property "Footprint" "antmicro-footprints:C_0402_1005Metric"
			(at 204.47 128.27 0)
			(effects
				(font
					(size 1.27 1.27)
					(thickness 0.15)
				)
				(justify left bottom)
				(hide yes)
			)
		)
		(property "Datasheet" "https://www.murata.com/products/productdetail?partno=GRM155R71H103KA88%23"
			(at 207.01 128.27 0)
			(effects
				(font
					(size 1.27 1.27)
					(thickness 0.15)
				)
				(justify left bottom)
				(hide yes)
			)
		)
		(property "Description" ""
			(at 191.77 107.95 0)
			(effects
				(font
					(size 1.27 1.27)
				)
				(hide yes)
			)
		)
		(property "Manufacturer" "Murata"
			(at 212.09 128.27 0)
			(effects
				(font
					(size 1.27 1.27)
					(thickness 0.15)
				)
				(justify left bottom)
				(hide yes)
			)
		)
		(property "MPN" "GRM155R71H103KA88D"
			(at 209.55 128.27 0)
			(effects
				(font
					(size 1.27 1.27)
					(thickness 0.15)
				)
				(justify left bottom)
				(hide yes)
			)
		)
		(property "Val" "10n"
			(at 191.135 112.395 90)
			(effects
				(font
					(size 1.27 1.27)
					(thickness 0.15)
				)
				(justify left)
			)
		)
		(property "License" "Apache-2.0"
			(at 214.63 128.27 0)
			(effects
				(font
					(size 1.27 1.27)
					(thickness 0.15)
				)
				(justify left bottom)
				(hide yes)
			)
		)
		(property "Author" "Antmicro"
			(at 217.17 128.27 0)
			(effects
				(font
					(size 1.27 1.27)
					(thickness 0.15)
				)
				(justify left bottom)
				(hide yes)
			)
		)
		(property "Voltage" "50V"
			(at 219.71 128.27 0)
			(effects
				(font
					(size 1.27 1.27)
				)
				(justify left bottom)
				(hide yes)
			)
		)
		(property "Dielectric" "X7R"
			(at 222.25 128.27 0)
			(effects
				(font
					(size 1.27 1.27)
				)
				(justify left bottom)
				(hide yes)
			)
		)
		(pin "1"
		)
		(pin "2"
		)
		(instances
			(project "data-center-rdimm-ddr5-tester"
				(path ""
					(reference "C151")
					(unit 1)
				)
			)
		)
	)
	(symbol
		(lib_id "antmicroCapacitors0402:C_4u7_0402")
		(at 46.99 128.27 270)
		(unit 1)
		(exclude_from_sim no)
		(in_bom yes)
		(on_board yes)
		(dnp no)
		(property "Reference" "C155"
			(at 47.625 128.905 90)
			(effects
				(font
					(size 1.27 1.27)
				)
				(justify left)
			)
		)
		(property "Value" "C_4u7_0402"
			(at 36.83 148.59 0)
			(effects
				(font
					(size 1.27 1.27)
					(thickness 0.15)
				)
				(justify left bottom)
				(hide yes)
			)
		)
		(property "Footprint" "antmicro-footprints:C_0402_1005Metric"
			(at 34.29 148.59 0)
			(effects
				(font
					(size 1.27 1.27)
					(thickness 0.15)
				)
				(justify left bottom)
				(hide yes)
			)
		)
		(property "Datasheet" "https://www.murata.com/products/productdetail?partno=GRM155R61A475MEAA%23"
			(at 31.75 148.59 0)
			(effects
				(font
					(size 1.27 1.27)
					(thickness 0.15)
				)
				(justify left bottom)
				(hide yes)
			)
		)
		(property "Description" ""
			(at 46.99 128.27 0)
			(effects
				(font
					(size 1.27 1.27)
				)
				(hide yes)
			)
		)
		(property "Manufacturer" "Murata"
			(at 26.67 148.59 0)
			(effects
				(font
					(size 1.27 1.27)
					(thickness 0.15)
				)
				(justify left bottom)
				(hide yes)
			)
		)
		(property "MPN" "GRM155R61A475MEAAD"
			(at 29.21 148.59 0)
			(effects
				(font
					(size 1.27 1.27)
					(thickness 0.15)
				)
				(justify left bottom)
				(hide yes)
			)
		)
		(property "Val" "4u7"
			(at 47.625 132.715 90)
			(effects
				(font
					(size 1.27 1.27)
					(thickness 0.15)
				)
				(justify left)
			)
		)
		(property "License" "Apache-2.0"
			(at 24.13 148.59 0)
			(effects
				(font
					(size 1.27 1.27)
					(thickness 0.15)
				)
				(justify left bottom)
				(hide yes)
			)
		)
		(property "Author" "Antmicro"
			(at 21.59 148.59 0)
			(effects
				(font
					(size 1.27 1.27)
					(thickness 0.15)
				)
				(justify left bottom)
				(hide yes)
			)
		)
		(property "Voltage" ""
			(at 19.05 148.59 0)
			(effects
				(font
					(size 1.27 1.27)
				)
				(justify left bottom)
				(hide yes)
			)
		)
		(property "Dielectric" ""
			(at 16.51 148.59 0)
			(effects
				(font
					(size 1.27 1.27)
				)
				(justify left bottom)
				(hide yes)
			)
		)
		(pin "1"
		)
		(pin "2"
		)
		(instances
			(project "data-center-rdimm-ddr5-tester"
				(path ""
					(reference "C155")
					(unit 1)
				)
			)
		)
	)
	(symbol
		(lib_id "antmicroCapacitors0402:C_470n_0402")
		(at 208.28 107.95 90)
		(mirror x)
		(unit 1)
		(exclude_from_sim no)
		(in_bom yes)
		(on_board yes)
		(dnp no)
		(property "Reference" "C149"
			(at 207.645 108.585 90)
			(effects
				(font
					(size 1.27 1.27)
				)
				(justify left)
			)
		)
		(property "Value" "C_470n_0402"
			(at 218.44 128.27 0)
			(effects
				(font
					(size 1.27 1.27)
					(thickness 0.15)
				)
				(justify left bottom)
				(hide yes)
			)
		)
		(property "Footprint" "antmicro-footprints:C_0402_1005Metric"
			(at 220.98 128.27 0)
			(effects
				(font
					(size 1.27 1.27)
					(thickness 0.15)
				)
				(justify left bottom)
				(hide yes)
			)
		)
		(property "Datasheet" "https://product.tdk.com/en/search/capacitor/ceramic/mlcc/info?part_no=C1005X5R1E474M050BB"
			(at 223.52 128.27 0)
			(effects
				(font
					(size 1.27 1.27)
					(thickness 0.15)
				)
				(justify left bottom)
				(hide yes)
			)
		)
		(property "Description" ""
			(at 208.28 107.95 0)
			(effects
				(font
					(size 1.27 1.27)
				)
				(hide yes)
			)
		)
		(property "Manufacturer" "TDK"
			(at 228.6 128.27 0)
			(effects
				(font
					(size 1.27 1.27)
					(thickness 0.15)
				)
				(justify left bottom)
				(hide yes)
			)
		)
		(property "MPN" "C1005X5R1E474M050BB"
			(at 226.06 128.27 0)
			(effects
				(font
					(size 1.27 1.27)
					(thickness 0.15)
				)
				(justify left bottom)
				(hide yes)
			)
		)
		(property "Val" "470n"
			(at 207.645 112.395 90)
			(effects
				(font
					(size 1.27 1.27)
					(thickness 0.15)
				)
				(justify left)
			)
		)
		(property "License" "Apache-2.0"
			(at 231.14 128.27 0)
			(effects
				(font
					(size 1.27 1.27)
					(thickness 0.15)
				)
				(justify left bottom)
				(hide yes)
			)
		)
		(property "Author" "Antmicro"
			(at 233.68 128.27 0)
			(effects
				(font
					(size 1.27 1.27)
					(thickness 0.15)
				)
				(justify left bottom)
				(hide yes)
			)
		)
		(property "Voltage" ""
			(at 236.22 128.27 0)
			(effects
				(font
					(size 1.27 1.27)
				)
				(justify left bottom)
				(hide yes)
			)
		)
		(property "Dielectric" ""
			(at 238.76 128.27 0)
			(effects
				(font
					(size 1.27 1.27)
				)
				(justify left bottom)
				(hide yes)
			)
		)
		(pin "1"
		)
		(pin "2"
		)
		(instances
			(project "data-center-rdimm-ddr5-tester"
				(path ""
					(reference "C149")
					(unit 1)
				)
			)
		)
	)
	(symbol
		(lib_id "antmicroCapacitors0402:C_4u7_0402")
		(at 241.3 107.95 90)
		(mirror x)
		(unit 1)
		(exclude_from_sim no)
		(in_bom yes)
		(on_board yes)
		(dnp no)
		(property "Reference" "C139"
			(at 240.665 108.585 90)
			(effects
				(font
					(size 1.27 1.27)
				)
				(justify left)
			)
		)
		(property "Value" "C_4u7_0402"
			(at 251.46 128.27 0)
			(effects
				(font
					(size 1.27 1.27)
					(thickness 0.15)
				)
				(justify left bottom)
				(hide yes)
			)
		)
		(property "Footprint" "antmicro-footprints:C_0402_1005Metric"
			(at 254 128.27 0)
			(effects
				(font
					(size 1.27 1.27)
					(thickness 0.15)
				)
				(justify left bottom)
				(hide yes)
			)
		)
		(property "Datasheet" "https://www.murata.com/products/productdetail?partno=GRM155R61A475MEAA%23"
			(at 256.54 128.27 0)
			(effects
				(font
					(size 1.27 1.27)
					(thickness 0.15)
				)
				(justify left bottom)
				(hide yes)
			)
		)
		(property "Description" ""
			(at 241.3 107.95 0)
			(effects
				(font
					(size 1.27 1.27)
				)
				(hide yes)
			)
		)
		(property "Manufacturer" "Murata"
			(at 261.62 128.27 0)
			(effects
				(font
					(size 1.27 1.27)
					(thickness 0.15)
				)
				(justify left bottom)
				(hide yes)
			)
		)
		(property "MPN" "GRM155R61A475MEAAD"
			(at 259.08 128.27 0)
			(effects
				(font
					(size 1.27 1.27)
					(thickness 0.15)
				)
				(justify left bottom)
				(hide yes)
			)
		)
		(property "Val" "4u7"
			(at 240.665 112.395 90)
			(effects
				(font
					(size 1.27 1.27)
					(thickness 0.15)
				)
				(justify left)
			)
		)
		(property "License" "Apache-2.0"
			(at 264.16 128.27 0)
			(effects
				(font
					(size 1.27 1.27)
					(thickness 0.15)
				)
				(justify left bottom)
				(hide yes)
			)
		)
		(property "Author" "Antmicro"
			(at 266.7 128.27 0)
			(effects
				(font
					(size 1.27 1.27)
					(thickness 0.15)
				)
				(justify left bottom)
				(hide yes)
			)
		)
		(property "Voltage" ""
			(at 269.24 128.27 0)
			(effects
				(font
					(size 1.27 1.27)
				)
				(justify left bottom)
				(hide yes)
			)
		)
		(property "Dielectric" ""
			(at 271.78 128.27 0)
			(effects
				(font
					(size 1.27 1.27)
				)
				(justify left bottom)
				(hide yes)
			)
		)
		(pin "1"
		)
		(pin "2"
		)
		(instances
			(project "data-center-rdimm-ddr5-tester"
				(path ""
					(reference "C139")
					(unit 1)
				)
			)
		)
	)
	(symbol
		(lib_id "antmicroCapacitors0402:C_470n_0402")
		(at 232.41 107.95 90)
		(mirror x)
		(unit 1)
		(exclude_from_sim no)
		(in_bom yes)
		(on_board yes)
		(dnp no)
		(property "Reference" "C142"
			(at 231.775 108.585 90)
			(effects
				(font
					(size 1.27 1.27)
				)
				(justify left)
			)
		)
		(property "Value" "C_470n_0402"
			(at 242.57 128.27 0)
			(effects
				(font
					(size 1.27 1.27)
					(thickness 0.15)
				)
				(justify left bottom)
				(hide yes)
			)
		)
		(property "Footprint" "antmicro-footprints:C_0402_1005Metric"
			(at 245.11 128.27 0)
			(effects
				(font
					(size 1.27 1.27)
					(thickness 0.15)
				)
				(justify left bottom)
				(hide yes)
			)
		)
		(property "Datasheet" "https://product.tdk.com/en/search/capacitor/ceramic/mlcc/info?part_no=C1005X5R1E474M050BB"
			(at 247.65 128.27 0)
			(effects
				(font
					(size 1.27 1.27)
					(thickness 0.15)
				)
				(justify left bottom)
				(hide yes)
			)
		)
		(property "Description" ""
			(at 232.41 107.95 0)
			(effects
				(font
					(size 1.27 1.27)
				)
				(hide yes)
			)
		)
		(property "Manufacturer" "TDK"
			(at 252.73 128.27 0)
			(effects
				(font
					(size 1.27 1.27)
					(thickness 0.15)
				)
				(justify left bottom)
				(hide yes)
			)
		)
		(property "MPN" "C1005X5R1E474M050BB"
			(at 250.19 128.27 0)
			(effects
				(font
					(size 1.27 1.27)
					(thickness 0.15)
				)
				(justify left bottom)
				(hide yes)
			)
		)
		(property "Val" "470n"
			(at 231.775 112.395 90)
			(effects
				(font
					(size 1.27 1.27)
					(thickness 0.15)
				)
				(justify left)
			)
		)
		(property "License" "Apache-2.0"
			(at 255.27 128.27 0)
			(effects
				(font
					(size 1.27 1.27)
					(thickness 0.15)
				)
				(justify left bottom)
				(hide yes)
			)
		)
		(property "Author" "Antmicro"
			(at 257.81 128.27 0)
			(effects
				(font
					(size 1.27 1.27)
					(thickness 0.15)
				)
				(justify left bottom)
				(hide yes)
			)
		)
		(property "Voltage" ""
			(at 260.35 128.27 0)
			(effects
				(font
					(size 1.27 1.27)
				)
				(justify left bottom)
				(hide yes)
			)
		)
		(property "Dielectric" ""
			(at 262.89 128.27 0)
			(effects
				(font
					(size 1.27 1.27)
				)
				(justify left bottom)
				(hide yes)
			)
		)
		(pin "1"
		)
		(pin "2"
		)
		(instances
			(project "data-center-rdimm-ddr5-tester"
				(path ""
					(reference "C142")
					(unit 1)
				)
			)
		)
	)
	(symbol
		(lib_id "antmicroCapacitors0402:C_470n_0402")
		(at 224.79 107.95 90)
		(mirror x)
		(unit 1)
		(exclude_from_sim no)
		(in_bom yes)
		(on_board yes)
		(dnp no)
		(property "Reference" "C145"
			(at 224.155 108.585 90)
			(effects
				(font
					(size 1.27 1.27)
				)
				(justify left)
			)
		)
		(property "Value" "C_470n_0402"
			(at 234.95 128.27 0)
			(effects
				(font
					(size 1.27 1.27)
					(thickness 0.15)
				)
				(justify left bottom)
				(hide yes)
			)
		)
		(property "Footprint" "antmicro-footprints:C_0402_1005Metric"
			(at 237.49 128.27 0)
			(effects
				(font
					(size 1.27 1.27)
					(thickness 0.15)
				)
				(justify left bottom)
				(hide yes)
			)
		)
		(property "Datasheet" "https://product.tdk.com/en/search/capacitor/ceramic/mlcc/info?part_no=C1005X5R1E474M050BB"
			(at 240.03 128.27 0)
			(effects
				(font
					(size 1.27 1.27)
					(thickness 0.15)
				)
				(justify left bottom)
				(hide yes)
			)
		)
		(property "Description" ""
			(at 224.79 107.95 0)
			(effects
				(font
					(size 1.27 1.27)
				)
				(hide yes)
			)
		)
		(property "Manufacturer" "TDK"
			(at 245.11 128.27 0)
			(effects
				(font
					(size 1.27 1.27)
					(thickness 0.15)
				)
				(justify left bottom)
				(hide yes)
			)
		)
		(property "MPN" "C1005X5R1E474M050BB"
			(at 242.57 128.27 0)
			(effects
				(font
					(size 1.27 1.27)
					(thickness 0.15)
				)
				(justify left bottom)
				(hide yes)
			)
		)
		(property "Val" "470n"
			(at 224.155 112.395 90)
			(effects
				(font
					(size 1.27 1.27)
					(thickness 0.15)
				)
				(justify left)
			)
		)
		(property "License" "Apache-2.0"
			(at 247.65 128.27 0)
			(effects
				(font
					(size 1.27 1.27)
					(thickness 0.15)
				)
				(justify left bottom)
				(hide yes)
			)
		)
		(property "Author" "Antmicro"
			(at 250.19 128.27 0)
			(effects
				(font
					(size 1.27 1.27)
					(thickness 0.15)
				)
				(justify left bottom)
				(hide yes)
			)
		)
		(property "Voltage" ""
			(at 252.73 128.27 0)
			(effects
				(font
					(size 1.27 1.27)
				)
				(justify left bottom)
				(hide yes)
			)
		)
		(property "Dielectric" ""
			(at 255.27 128.27 0)
			(effects
				(font
					(size 1.27 1.27)
				)
				(justify left bottom)
				(hide yes)
			)
		)
		(pin "1"
		)
		(pin "2"
		)
		(instances
			(project "data-center-rdimm-ddr5-tester"
				(path ""
					(reference "C145")
					(unit 1)
				)
			)
		)
	)
	(symbol
		(lib_id "antmicroCapacitors0402:C_470n_0402")
		(at 215.9 107.95 90)
		(mirror x)
		(unit 1)
		(exclude_from_sim no)
		(in_bom yes)
		(on_board yes)
		(dnp no)
		(property "Reference" "C148"
			(at 215.265 108.585 90)
			(effects
				(font
					(size 1.27 1.27)
				)
				(justify left)
			)
		)
		(property "Value" "C_470n_0402"
			(at 226.06 128.27 0)
			(effects
				(font
					(size 1.27 1.27)
					(thickness 0.15)
				)
				(justify left bottom)
				(hide yes)
			)
		)
		(property "Footprint" "antmicro-footprints:C_0402_1005Metric"
			(at 228.6 128.27 0)
			(effects
				(font
					(size 1.27 1.27)
					(thickness 0.15)
				)
				(justify left bottom)
				(hide yes)
			)
		)
		(property "Datasheet" "https://product.tdk.com/en/search/capacitor/ceramic/mlcc/info?part_no=C1005X5R1E474M050BB"
			(at 231.14 128.27 0)
			(effects
				(font
					(size 1.27 1.27)
					(thickness 0.15)
				)
				(justify left bottom)
				(hide yes)
			)
		)
		(property "Description" ""
			(at 215.9 107.95 0)
			(effects
				(font
					(size 1.27 1.27)
				)
				(hide yes)
			)
		)
		(property "Manufacturer" "TDK"
			(at 236.22 128.27 0)
			(effects
				(font
					(size 1.27 1.27)
					(thickness 0.15)
				)
				(justify left bottom)
				(hide yes)
			)
		)
		(property "MPN" "C1005X5R1E474M050BB"
			(at 233.68 128.27 0)
			(effects
				(font
					(size 1.27 1.27)
					(thickness 0.15)
				)
				(justify left bottom)
				(hide yes)
			)
		)
		(property "Val" "470n"
			(at 215.265 112.395 90)
			(effects
				(font
					(size 1.27 1.27)
					(thickness 0.15)
				)
				(justify left)
			)
		)
		(property "License" "Apache-2.0"
			(at 238.76 128.27 0)
			(effects
				(font
					(size 1.27 1.27)
					(thickness 0.15)
				)
				(justify left bottom)
				(hide yes)
			)
		)
		(property "Author" "Antmicro"
			(at 241.3 128.27 0)
			(effects
				(font
					(size 1.27 1.27)
					(thickness 0.15)
				)
				(justify left bottom)
				(hide yes)
			)
		)
		(property "Voltage" ""
			(at 243.84 128.27 0)
			(effects
				(font
					(size 1.27 1.27)
				)
				(justify left bottom)
				(hide yes)
			)
		)
		(property "Dielectric" ""
			(at 246.38 128.27 0)
			(effects
				(font
					(size 1.27 1.27)
				)
				(justify left bottom)
				(hide yes)
			)
		)
		(pin "1"
		)
		(pin "2"
		)
		(instances
			(project "data-center-rdimm-ddr5-tester"
				(path ""
					(reference "C148")
					(unit 1)
				)
			)
		)
	)
	(symbol
		(lib_id "antmicroCapacitors0402:C_4u7_0402")
		(at 54.61 128.27 270)
		(unit 1)
		(exclude_from_sim no)
		(in_bom yes)
		(on_board yes)
		(dnp no)
		(property "Reference" "C158"
			(at 55.245 128.905 90)
			(effects
				(font
					(size 1.27 1.27)
				)
				(justify left)
			)
		)
		(property "Value" "C_4u7_0402"
			(at 44.45 148.59 0)
			(effects
				(font
					(size 1.27 1.27)
					(thickness 0.15)
				)
				(justify left bottom)
				(hide yes)
			)
		)
		(property "Footprint" "antmicro-footprints:C_0402_1005Metric"
			(at 41.91 148.59 0)
			(effects
				(font
					(size 1.27 1.27)
					(thickness 0.15)
				)
				(justify left bottom)
				(hide yes)
			)
		)
		(property "Datasheet" "https://www.murata.com/products/productdetail?partno=GRM155R61A475MEAA%23"
			(at 39.37 148.59 0)
			(effects
				(font
					(size 1.27 1.27)
					(thickness 0.15)
				)
				(justify left bottom)
				(hide yes)
			)
		)
		(property "Description" ""
			(at 54.61 128.27 0)
			(effects
				(font
					(size 1.27 1.27)
				)
				(hide yes)
			)
		)
		(property "Manufacturer" "Murata"
			(at 34.29 148.59 0)
			(effects
				(font
					(size 1.27 1.27)
					(thickness 0.15)
				)
				(justify left bottom)
				(hide yes)
			)
		)
		(property "MPN" "GRM155R61A475MEAAD"
			(at 36.83 148.59 0)
			(effects
				(font
					(size 1.27 1.27)
					(thickness 0.15)
				)
				(justify left bottom)
				(hide yes)
			)
		)
		(property "Val" "4u7"
			(at 55.245 132.715 90)
			(effects
				(font
					(size 1.27 1.27)
					(thickness 0.15)
				)
				(justify left)
			)
		)
		(property "License" "Apache-2.0"
			(at 31.75 148.59 0)
			(effects
				(font
					(size 1.27 1.27)
					(thickness 0.15)
				)
				(justify left bottom)
				(hide yes)
			)
		)
		(property "Author" "Antmicro"
			(at 29.21 148.59 0)
			(effects
				(font
					(size 1.27 1.27)
					(thickness 0.15)
				)
				(justify left bottom)
				(hide yes)
			)
		)
		(property "Voltage" ""
			(at 26.67 148.59 0)
			(effects
				(font
					(size 1.27 1.27)
				)
				(justify left bottom)
				(hide yes)
			)
		)
		(property "Dielectric" ""
			(at 24.13 148.59 0)
			(effects
				(font
					(size 1.27 1.27)
				)
				(justify left bottom)
				(hide yes)
			)
		)
		(pin "1"
		)
		(pin "2"
		)
		(instances
			(project "data-center-rdimm-ddr5-tester"
				(path ""
					(reference "C158")
					(unit 1)
				)
			)
		)
	)
	(symbol
		(lib_id "antmicroCapacitors0402:C_4u7_0402")
		(at 38.1 128.27 270)
		(unit 1)
		(exclude_from_sim no)
		(in_bom yes)
		(on_board yes)
		(dnp no)
		(property "Reference" "C152"
			(at 38.735 128.905 90)
			(effects
				(font
					(size 1.27 1.27)
				)
				(justify left)
			)
		)
		(property "Value" "C_4u7_0402"
			(at 27.94 148.59 0)
			(effects
				(font
					(size 1.27 1.27)
					(thickness 0.15)
				)
				(justify left bottom)
				(hide yes)
			)
		)
		(property "Footprint" "antmicro-footprints:C_0402_1005Metric"
			(at 25.4 148.59 0)
			(effects
				(font
					(size 1.27 1.27)
					(thickness 0.15)
				)
				(justify left bottom)
				(hide yes)
			)
		)
		(property "Datasheet" "https://www.murata.com/products/productdetail?partno=GRM155R61A475MEAA%23"
			(at 22.86 148.59 0)
			(effects
				(font
					(size 1.27 1.27)
					(thickness 0.15)
				)
				(justify left bottom)
				(hide yes)
			)
		)
		(property "Description" ""
			(at 38.1 128.27 0)
			(effects
				(font
					(size 1.27 1.27)
				)
				(hide yes)
			)
		)
		(property "Manufacturer" "Murata"
			(at 17.78 148.59 0)
			(effects
				(font
					(size 1.27 1.27)
					(thickness 0.15)
				)
				(justify left bottom)
				(hide yes)
			)
		)
		(property "MPN" "GRM155R61A475MEAAD"
			(at 20.32 148.59 0)
			(effects
				(font
					(size 1.27 1.27)
					(thickness 0.15)
				)
				(justify left bottom)
				(hide yes)
			)
		)
		(property "Val" "4u7"
			(at 38.735 132.715 90)
			(effects
				(font
					(size 1.27 1.27)
					(thickness 0.15)
				)
				(justify left)
			)
		)
		(property "License" "Apache-2.0"
			(at 15.24 148.59 0)
			(effects
				(font
					(size 1.27 1.27)
					(thickness 0.15)
				)
				(justify left bottom)
				(hide yes)
			)
		)
		(property "Author" "Antmicro"
			(at 12.7 148.59 0)
			(effects
				(font
					(size 1.27 1.27)
					(thickness 0.15)
				)
				(justify left bottom)
				(hide yes)
			)
		)
		(property "Voltage" ""
			(at 10.16 148.59 0)
			(effects
				(font
					(size 1.27 1.27)
				)
				(justify left bottom)
				(hide yes)
			)
		)
		(property "Dielectric" ""
			(at 7.62 148.59 0)
			(effects
				(font
					(size 1.27 1.27)
				)
				(justify left bottom)
				(hide yes)
			)
		)
		(pin "1"
		)
		(pin "2"
		)
		(instances
			(project "data-center-rdimm-ddr5-tester"
				(path ""
					(reference "C152")
					(unit 1)
				)
			)
		)
	)
	(symbol
		(lib_id "antmicroCapacitors0402:C_4u7_0402")
		(at 52.07 106.68 270)
		(unit 1)
		(exclude_from_sim no)
		(in_bom yes)
		(on_board yes)
		(dnp no)
		(property "Reference" "C134"
			(at 52.705 107.315 90)
			(effects
				(font
					(size 1.27 1.27)
				)
				(justify left)
			)
		)
		(property "Value" "C_4u7_0402"
			(at 41.91 127 0)
			(effects
				(font
					(size 1.27 1.27)
					(thickness 0.15)
				)
				(justify left bottom)
				(hide yes)
			)
		)
		(property "Footprint" "antmicro-footprints:C_0402_1005Metric"
			(at 39.37 127 0)
			(effects
				(font
					(size 1.27 1.27)
					(thickness 0.15)
				)
				(justify left bottom)
				(hide yes)
			)
		)
		(property "Datasheet" "https://www.murata.com/products/productdetail?partno=GRM155R61A475MEAA%23"
			(at 36.83 127 0)
			(effects
				(font
					(size 1.27 1.27)
					(thickness 0.15)
				)
				(justify left bottom)
				(hide yes)
			)
		)
		(property "Description" ""
			(at 52.07 106.68 0)
			(effects
				(font
					(size 1.27 1.27)
				)
				(hide yes)
			)
		)
		(property "Manufacturer" "Murata"
			(at 31.75 127 0)
			(effects
				(font
					(size 1.27 1.27)
					(thickness 0.15)
				)
				(justify left bottom)
				(hide yes)
			)
		)
		(property "MPN" "GRM155R61A475MEAAD"
			(at 34.29 127 0)
			(effects
				(font
					(size 1.27 1.27)
					(thickness 0.15)
				)
				(justify left bottom)
				(hide yes)
			)
		)
		(property "Val" "4u7"
			(at 52.705 111.125 90)
			(effects
				(font
					(size 1.27 1.27)
					(thickness 0.15)
				)
				(justify left)
			)
		)
		(property "License" "Apache-2.0"
			(at 29.21 127 0)
			(effects
				(font
					(size 1.27 1.27)
					(thickness 0.15)
				)
				(justify left bottom)
				(hide yes)
			)
		)
		(property "Author" "Antmicro"
			(at 26.67 127 0)
			(effects
				(font
					(size 1.27 1.27)
					(thickness 0.15)
				)
				(justify left bottom)
				(hide yes)
			)
		)
		(property "Voltage" ""
			(at 24.13 127 0)
			(effects
				(font
					(size 1.27 1.27)
				)
				(justify left bottom)
				(hide yes)
			)
		)
		(property "Dielectric" ""
			(at 21.59 127 0)
			(effects
				(font
					(size 1.27 1.27)
				)
				(justify left bottom)
				(hide yes)
			)
		)
		(pin "1"
		)
		(pin "2"
		)
		(instances
			(project "data-center-rdimm-ddr5-tester"
				(path ""
					(reference "C134")
					(unit 1)
				)
			)
		)
	)
	(symbol
		(lib_id "antmicroCapacitors0402:C_470n_0402")
		(at 60.96 106.68 270)
		(unit 1)
		(exclude_from_sim no)
		(in_bom yes)
		(on_board yes)
		(dnp no)
		(property "Reference" "C138"
			(at 61.595 107.315 90)
			(effects
				(font
					(size 1.27 1.27)
				)
				(justify left)
			)
		)
		(property "Value" "C_470n_0402"
			(at 50.8 127 0)
			(effects
				(font
					(size 1.27 1.27)
					(thickness 0.15)
				)
				(justify left bottom)
				(hide yes)
			)
		)
		(property "Footprint" "antmicro-footprints:C_0402_1005Metric"
			(at 48.26 127 0)
			(effects
				(font
					(size 1.27 1.27)
					(thickness 0.15)
				)
				(justify left bottom)
				(hide yes)
			)
		)
		(property "Datasheet" "https://product.tdk.com/en/search/capacitor/ceramic/mlcc/info?part_no=C1005X5R1E474M050BB"
			(at 45.72 127 0)
			(effects
				(font
					(size 1.27 1.27)
					(thickness 0.15)
				)
				(justify left bottom)
				(hide yes)
			)
		)
		(property "Description" ""
			(at 60.96 106.68 0)
			(effects
				(font
					(size 1.27 1.27)
				)
				(hide yes)
			)
		)
		(property "Manufacturer" "TDK"
			(at 40.64 127 0)
			(effects
				(font
					(size 1.27 1.27)
					(thickness 0.15)
				)
				(justify left bottom)
				(hide yes)
			)
		)
		(property "MPN" "C1005X5R1E474M050BB"
			(at 43.18 127 0)
			(effects
				(font
					(size 1.27 1.27)
					(thickness 0.15)
				)
				(justify left bottom)
				(hide yes)
			)
		)
		(property "Val" "470n"
			(at 61.595 111.125 90)
			(effects
				(font
					(size 1.27 1.27)
					(thickness 0.15)
				)
				(justify left)
			)
		)
		(property "License" "Apache-2.0"
			(at 38.1 127 0)
			(effects
				(font
					(size 1.27 1.27)
					(thickness 0.15)
				)
				(justify left bottom)
				(hide yes)
			)
		)
		(property "Author" "Antmicro"
			(at 35.56 127 0)
			(effects
				(font
					(size 1.27 1.27)
					(thickness 0.15)
				)
				(justify left bottom)
				(hide yes)
			)
		)
		(property "Voltage" ""
			(at 33.02 127 0)
			(effects
				(font
					(size 1.27 1.27)
				)
				(justify left bottom)
				(hide yes)
			)
		)
		(property "Dielectric" ""
			(at 30.48 127 0)
			(effects
				(font
					(size 1.27 1.27)
				)
				(justify left bottom)
				(hide yes)
			)
		)
		(pin "1"
		)
		(pin "2"
		)
		(instances
			(project "data-center-rdimm-ddr5-tester"
				(path ""
					(reference "C138")
					(unit 1)
				)
			)
		)
	)
	(symbol
		(lib_id "antmicroCapacitors0402:C_10n_0402")
		(at 77.47 106.68 270)
		(unit 1)
		(exclude_from_sim no)
		(in_bom yes)
		(on_board yes)
		(dnp no)
		(property "Reference" "C144"
			(at 78.105 107.315 90)
			(effects
				(font
					(size 1.27 1.27)
				)
				(justify left)
			)
		)
		(property "Value" "C_10n_0402"
			(at 67.31 127 0)
			(effects
				(font
					(size 1.27 1.27)
					(thickness 0.15)
				)
				(justify left bottom)
				(hide yes)
			)
		)
		(property "Footprint" "antmicro-footprints:C_0402_1005Metric"
			(at 64.77 127 0)
			(effects
				(font
					(size 1.27 1.27)
					(thickness 0.15)
				)
				(justify left bottom)
				(hide yes)
			)
		)
		(property "Datasheet" "https://www.murata.com/products/productdetail?partno=GRM155R71H103KA88%23"
			(at 62.23 127 0)
			(effects
				(font
					(size 1.27 1.27)
					(thickness 0.15)
				)
				(justify left bottom)
				(hide yes)
			)
		)
		(property "Description" ""
			(at 77.47 106.68 0)
			(effects
				(font
					(size 1.27 1.27)
				)
				(hide yes)
			)
		)
		(property "Manufacturer" "Murata"
			(at 57.15 127 0)
			(effects
				(font
					(size 1.27 1.27)
					(thickness 0.15)
				)
				(justify left bottom)
				(hide yes)
			)
		)
		(property "MPN" "GRM155R71H103KA88D"
			(at 59.69 127 0)
			(effects
				(font
					(size 1.27 1.27)
					(thickness 0.15)
				)
				(justify left bottom)
				(hide yes)
			)
		)
		(property "Val" "10n"
			(at 78.105 111.125 90)
			(effects
				(font
					(size 1.27 1.27)
					(thickness 0.15)
				)
				(justify left)
			)
		)
		(property "License" "Apache-2.0"
			(at 54.61 127 0)
			(effects
				(font
					(size 1.27 1.27)
					(thickness 0.15)
				)
				(justify left bottom)
				(hide yes)
			)
		)
		(property "Author" "Antmicro"
			(at 52.07 127 0)
			(effects
				(font
					(size 1.27 1.27)
					(thickness 0.15)
				)
				(justify left bottom)
				(hide yes)
			)
		)
		(property "Voltage" "50V"
			(at 49.53 127 0)
			(effects
				(font
					(size 1.27 1.27)
				)
				(justify left bottom)
				(hide yes)
			)
		)
		(property "Dielectric" "X7R"
			(at 46.99 127 0)
			(effects
				(font
					(size 1.27 1.27)
				)
				(justify left bottom)
				(hide yes)
			)
		)
		(pin "1"
		)
		(pin "2"
		)
		(instances
			(project "data-center-rdimm-ddr5-tester"
				(path ""
					(reference "C144")
					(unit 1)
				)
			)
		)
	)
	(symbol
		(lib_id "antmicroCapacitors0402:C_10n_0402")
		(at 85.09 106.68 270)
		(unit 1)
		(exclude_from_sim no)
		(in_bom yes)
		(on_board yes)
		(dnp no)
		(property "Reference" "C147"
			(at 85.725 107.315 90)
			(effects
				(font
					(size 1.27 1.27)
				)
				(justify left)
			)
		)
		(property "Value" "C_10n_0402"
			(at 74.93 127 0)
			(effects
				(font
					(size 1.27 1.27)
					(thickness 0.15)
				)
				(justify left bottom)
				(hide yes)
			)
		)
		(property "Footprint" "antmicro-footprints:C_0402_1005Metric"
			(at 72.39 127 0)
			(effects
				(font
					(size 1.27 1.27)
					(thickness 0.15)
				)
				(justify left bottom)
				(hide yes)
			)
		)
		(property "Datasheet" "https://www.murata.com/products/productdetail?partno=GRM155R71H103KA88%23"
			(at 69.85 127 0)
			(effects
				(font
					(size 1.27 1.27)
					(thickness 0.15)
				)
				(justify left bottom)
				(hide yes)
			)
		)
		(property "Description" ""
			(at 85.09 106.68 0)
			(effects
				(font
					(size 1.27 1.27)
				)
				(hide yes)
			)
		)
		(property "Manufacturer" "Murata"
			(at 64.77 127 0)
			(effects
				(font
					(size 1.27 1.27)
					(thickness 0.15)
				)
				(justify left bottom)
				(hide yes)
			)
		)
		(property "MPN" "GRM155R71H103KA88D"
			(at 67.31 127 0)
			(effects
				(font
					(size 1.27 1.27)
					(thickness 0.15)
				)
				(justify left bottom)
				(hide yes)
			)
		)
		(property "Val" "10n"
			(at 85.725 111.125 90)
			(effects
				(font
					(size 1.27 1.27)
					(thickness 0.15)
				)
				(justify left)
			)
		)
		(property "License" "Apache-2.0"
			(at 62.23 127 0)
			(effects
				(font
					(size 1.27 1.27)
					(thickness 0.15)
				)
				(justify left bottom)
				(hide yes)
			)
		)
		(property "Author" "Antmicro"
			(at 59.69 127 0)
			(effects
				(font
					(size 1.27 1.27)
					(thickness 0.15)
				)
				(justify left bottom)
				(hide yes)
			)
		)
		(property "Voltage" "50V"
			(at 57.15 127 0)
			(effects
				(font
					(size 1.27 1.27)
				)
				(justify left bottom)
				(hide yes)
			)
		)
		(property "Dielectric" "X7R"
			(at 54.61 127 0)
			(effects
				(font
					(size 1.27 1.27)
				)
				(justify left bottom)
				(hide yes)
			)
		)
		(pin "1"
		)
		(pin "2"
		)
		(instances
			(project "data-center-rdimm-ddr5-tester"
				(path ""
					(reference "C147")
					(unit 1)
				)
			)
		)
	)
	(symbol
		(lib_id "antmicroCapacitors0402:C_10n_0402")
		(at 68.58 106.68 270)
		(unit 1)
		(exclude_from_sim no)
		(in_bom yes)
		(on_board yes)
		(dnp no)
		(property "Reference" "C141"
			(at 69.215 107.315 90)
			(effects
				(font
					(size 1.27 1.27)
				)
				(justify left)
			)
		)
		(property "Value" "C_10n_0402"
			(at 58.42 127 0)
			(effects
				(font
					(size 1.27 1.27)
					(thickness 0.15)
				)
				(justify left bottom)
				(hide yes)
			)
		)
		(property "Footprint" "antmicro-footprints:C_0402_1005Metric"
			(at 55.88 127 0)
			(effects
				(font
					(size 1.27 1.27)
					(thickness 0.15)
				)
				(justify left bottom)
				(hide yes)
			)
		)
		(property "Datasheet" "https://www.murata.com/products/productdetail?partno=GRM155R71H103KA88%23"
			(at 53.34 127 0)
			(effects
				(font
					(size 1.27 1.27)
					(thickness 0.15)
				)
				(justify left bottom)
				(hide yes)
			)
		)
		(property "Description" ""
			(at 68.58 106.68 0)
			(effects
				(font
					(size 1.27 1.27)
				)
				(hide yes)
			)
		)
		(property "Manufacturer" "Murata"
			(at 48.26 127 0)
			(effects
				(font
					(size 1.27 1.27)
					(thickness 0.15)
				)
				(justify left bottom)
				(hide yes)
			)
		)
		(property "MPN" "GRM155R71H103KA88D"
			(at 50.8 127 0)
			(effects
				(font
					(size 1.27 1.27)
					(thickness 0.15)
				)
				(justify left bottom)
				(hide yes)
			)
		)
		(property "Val" "10n"
			(at 69.215 111.125 90)
			(effects
				(font
					(size 1.27 1.27)
					(thickness 0.15)
				)
				(justify left)
			)
		)
		(property "License" "Apache-2.0"
			(at 45.72 127 0)
			(effects
				(font
					(size 1.27 1.27)
					(thickness 0.15)
				)
				(justify left bottom)
				(hide yes)
			)
		)
		(property "Author" "Antmicro"
			(at 43.18 127 0)
			(effects
				(font
					(size 1.27 1.27)
					(thickness 0.15)
				)
				(justify left bottom)
				(hide yes)
			)
		)
		(property "Voltage" "50V"
			(at 40.64 127 0)
			(effects
				(font
					(size 1.27 1.27)
				)
				(justify left bottom)
				(hide yes)
			)
		)
		(property "Dielectric" "X7R"
			(at 38.1 127 0)
			(effects
				(font
					(size 1.27 1.27)
				)
				(justify left bottom)
				(hide yes)
			)
		)
		(pin "1"
		)
		(pin "2"
		)
		(instances
			(project "data-center-rdimm-ddr5-tester"
				(path ""
					(reference "C141")
					(unit 1)
				)
			)
		)
	)
	(symbol
		(lib_id "antmicroCapacitors0402:C_4u7_0402")
		(at 191.77 149.86 270)
		(mirror x)
		(unit 1)
		(exclude_from_sim no)
		(in_bom yes)
		(on_board yes)
		(dnp no)
		(fields_autoplaced yes)
		(property "Reference" "C159"
			(at 192.405 145.415 90)
			(effects
				(font
					(size 1.27 1.27)
				)
				(justify left)
			)
		)
		(property "Value" "C_4u7_0402"
			(at 181.61 129.54 0)
			(effects
				(font
					(size 1.27 1.27)
					(thickness 0.15)
				)
				(justify left bottom)
				(hide yes)
			)
		)
		(property "Footprint" "antmicro-footprints:C_0402_1005Metric"
			(at 179.07 129.54 0)
			(effects
				(font
					(size 1.27 1.27)
					(thickness 0.15)
				)
				(justify left bottom)
				(hide yes)
			)
		)
		(property "Datasheet" "https://www.murata.com/products/productdetail?partno=GRM155R61A475MEAA%23"
			(at 176.53 129.54 0)
			(effects
				(font
					(size 1.27 1.27)
					(thickness 0.15)
				)
				(justify left bottom)
				(hide yes)
			)
		)
		(property "Description" ""
			(at 191.77 149.86 0)
			(effects
				(font
					(size 1.27 1.27)
				)
				(hide yes)
			)
		)
		(property "Manufacturer" "Murata"
			(at 171.45 129.54 0)
			(effects
				(font
					(size 1.27 1.27)
					(thickness 0.15)
				)
				(justify left bottom)
				(hide yes)
			)
		)
		(property "MPN" "GRM155R61A475MEAAD"
			(at 173.99 129.54 0)
			(effects
				(font
					(size 1.27 1.27)
					(thickness 0.15)
				)
				(justify left bottom)
				(hide yes)
			)
		)
		(property "Val" "4u7"
			(at 192.405 149.225 90)
			(effects
				(font
					(size 1.27 1.27)
					(thickness 0.15)
				)
				(justify left)
			)
		)
		(property "License" "Apache-2.0"
			(at 168.91 129.54 0)
			(effects
				(font
					(size 1.27 1.27)
					(thickness 0.15)
				)
				(justify left bottom)
				(hide yes)
			)
		)
		(property "Author" "Antmicro"
			(at 166.37 129.54 0)
			(effects
				(font
					(size 1.27 1.27)
					(thickness 0.15)
				)
				(justify left bottom)
				(hide yes)
			)
		)
		(property "Voltage" ""
			(at 163.83 129.54 0)
			(effects
				(font
					(size 1.27 1.27)
				)
				(justify left bottom)
				(hide yes)
			)
		)
		(property "Dielectric" ""
			(at 161.29 129.54 0)
			(effects
				(font
					(size 1.27 1.27)
				)
				(justify left bottom)
				(hide yes)
			)
		)
		(pin "1"
		)
		(pin "2"
		)
		(instances
			(project "data-center-rdimm-ddr5-tester"
				(path ""
					(reference "C159")
					(unit 1)
				)
			)
		)
	)
	(symbol
		(lib_id "antmicroCapacitors0402:C_10n_0402")
		(at 175.26 149.86 270)
		(mirror x)
		(unit 1)
		(exclude_from_sim no)
		(in_bom yes)
		(on_board yes)
		(dnp no)
		(fields_autoplaced yes)
		(property "Reference" "C154"
			(at 175.895 145.415 90)
			(effects
				(font
					(size 1.27 1.27)
				)
				(justify left)
			)
		)
		(property "Value" "C_10n_0402"
			(at 165.1 129.54 0)
			(effects
				(font
					(size 1.27 1.27)
					(thickness 0.15)
				)
				(justify left bottom)
				(hide yes)
			)
		)
		(property "Footprint" "antmicro-footprints:C_0402_1005Metric"
			(at 162.56 129.54 0)
			(effects
				(font
					(size 1.27 1.27)
					(thickness 0.15)
				)
				(justify left bottom)
				(hide yes)
			)
		)
		(property "Datasheet" "https://www.murata.com/products/productdetail?partno=GRM155R71H103KA88%23"
			(at 160.02 129.54 0)
			(effects
				(font
					(size 1.27 1.27)
					(thickness 0.15)
				)
				(justify left bottom)
				(hide yes)
			)
		)
		(property "Description" ""
			(at 175.26 149.86 0)
			(effects
				(font
					(size 1.27 1.27)
				)
				(hide yes)
			)
		)
		(property "Manufacturer" "Murata"
			(at 154.94 129.54 0)
			(effects
				(font
					(size 1.27 1.27)
					(thickness 0.15)
				)
				(justify left bottom)
				(hide yes)
			)
		)
		(property "MPN" "GRM155R71H103KA88D"
			(at 157.48 129.54 0)
			(effects
				(font
					(size 1.27 1.27)
					(thickness 0.15)
				)
				(justify left bottom)
				(hide yes)
			)
		)
		(property "Val" "10n"
			(at 175.895 149.225 90)
			(effects
				(font
					(size 1.27 1.27)
					(thickness 0.15)
				)
				(justify left)
			)
		)
		(property "License" "Apache-2.0"
			(at 152.4 129.54 0)
			(effects
				(font
					(size 1.27 1.27)
					(thickness 0.15)
				)
				(justify left bottom)
				(hide yes)
			)
		)
		(property "Author" "Antmicro"
			(at 149.86 129.54 0)
			(effects
				(font
					(size 1.27 1.27)
					(thickness 0.15)
				)
				(justify left bottom)
				(hide yes)
			)
		)
		(property "Voltage" "50V"
			(at 147.32 129.54 0)
			(effects
				(font
					(size 1.27 1.27)
				)
				(justify left bottom)
				(hide yes)
			)
		)
		(property "Dielectric" "X7R"
			(at 144.78 129.54 0)
			(effects
				(font
					(size 1.27 1.27)
				)
				(justify left bottom)
				(hide yes)
			)
		)
		(pin "1"
		)
		(pin "2"
		)
		(instances
			(project "data-center-rdimm-ddr5-tester"
				(path ""
					(reference "C154")
					(unit 1)
				)
			)
		)
	)
	(symbol
		(lib_id "antmicropower:GND")
		(at 241.3 114.3 0)
		(mirror y)
		(unit 1)
		(exclude_from_sim no)
		(in_bom yes)
		(on_board yes)
		(dnp no)
		(fields_autoplaced yes)
		(property "Reference" "#PWR0245"
			(at 241.3 120.65 0)
			(effects
				(font
					(size 1.27 1.27)
				)
				(hide yes)
			)
		)
		(property "Value" "GND"
			(at 243.205 118.745 0)
			(effects
				(font
					(size 1.27 1.27)
					(thickness 0.15)
				)
				(justify left bottom)
			)
		)
		(property "Footprint" ""
			(at 232.41 121.92 0)
			(effects
				(font
					(size 1.27 1.27)
					(thickness 0.15)
				)
				(justify left bottom)
				(hide yes)
			)
		)
		(property "Datasheet" ""
			(at 232.41 127 0)
			(effects
				(font
					(size 1.27 1.27)
					(thickness 0.15)
				)
				(justify left bottom)
				(hide yes)
			)
		)
		(property "Description" ""
			(at 241.3 114.3 0)
			(effects
				(font
					(size 1.27 1.27)
				)
				(hide yes)
			)
		)
		(property "Author" "Antmicro"
			(at 232.41 119.38 0)
			(effects
				(font
					(size 1.27 1.27)
					(thickness 0.15)
				)
				(justify left bottom)
				(hide yes)
			)
		)
		(property "License" "Apache-2.0"
			(at 232.41 121.92 0)
			(effects
				(font
					(size 1.27 1.27)
					(thickness 0.15)
				)
				(justify left bottom)
				(hide yes)
			)
		)
		(pin "1"
		)
		(instances
			(project "data-center-rdimm-ddr5-tester"
				(path ""
					(reference "#PWR0245")
					(unit 1)
				)
			)
		)
	)
	(symbol
		(lib_id "antmicropower:GND")
		(at 38.1 134.62 0)
		(unit 1)
		(exclude_from_sim no)
		(in_bom yes)
		(on_board yes)
		(dnp no)
		(fields_autoplaced yes)
		(property "Reference" "#PWR0250"
			(at 38.1 140.97 0)
			(effects
				(font
					(size 1.27 1.27)
				)
				(hide yes)
			)
		)
		(property "Value" "GND"
			(at 36.195 139.065 0)
			(effects
				(font
					(size 1.27 1.27)
					(thickness 0.15)
				)
				(justify left bottom)
			)
		)
		(property "Footprint" ""
			(at 46.99 142.24 0)
			(effects
				(font
					(size 1.27 1.27)
					(thickness 0.15)
				)
				(justify left bottom)
				(hide yes)
			)
		)
		(property "Datasheet" ""
			(at 46.99 147.32 0)
			(effects
				(font
					(size 1.27 1.27)
					(thickness 0.15)
				)
				(justify left bottom)
				(hide yes)
			)
		)
		(property "Description" ""
			(at 38.1 134.62 0)
			(effects
				(font
					(size 1.27 1.27)
				)
				(hide yes)
			)
		)
		(property "Author" "Antmicro"
			(at 46.99 139.7 0)
			(effects
				(font
					(size 1.27 1.27)
					(thickness 0.15)
				)
				(justify left bottom)
				(hide yes)
			)
		)
		(property "License" "Apache-2.0"
			(at 46.99 142.24 0)
			(effects
				(font
					(size 1.27 1.27)
					(thickness 0.15)
				)
				(justify left bottom)
				(hide yes)
			)
		)
		(pin "1"
		)
		(instances
			(project "data-center-rdimm-ddr5-tester"
				(path ""
					(reference "#PWR0250")
					(unit 1)
				)
			)
		)
	)
	(symbol
		(lib_id "antmicropower:GND")
		(at 52.07 113.03 0)
		(unit 1)
		(exclude_from_sim no)
		(in_bom yes)
		(on_board yes)
		(dnp no)
		(property "Reference" "#PWR0241"
			(at 52.07 119.38 0)
			(effects
				(font
					(size 1.27 1.27)
				)
				(hide yes)
			)
		)
		(property "Value" "GND"
			(at 50.165 117.475 0)
			(effects
				(font
					(size 1.27 1.27)
					(thickness 0.15)
				)
				(justify left bottom)
			)
		)
		(property "Footprint" ""
			(at 60.96 120.65 0)
			(effects
				(font
					(size 1.27 1.27)
					(thickness 0.15)
				)
				(justify left bottom)
				(hide yes)
			)
		)
		(property "Datasheet" ""
			(at 60.96 125.73 0)
			(effects
				(font
					(size 1.27 1.27)
					(thickness 0.15)
				)
				(justify left bottom)
				(hide yes)
			)
		)
		(property "Description" ""
			(at 52.07 113.03 0)
			(effects
				(font
					(size 1.27 1.27)
				)
				(hide yes)
			)
		)
		(property "Author" "Antmicro"
			(at 60.96 118.11 0)
			(effects
				(font
					(size 1.27 1.27)
					(thickness 0.15)
				)
				(justify left bottom)
				(hide yes)
			)
		)
		(property "License" "Apache-2.0"
			(at 60.96 120.65 0)
			(effects
				(font
					(size 1.27 1.27)
					(thickness 0.15)
				)
				(justify left bottom)
				(hide yes)
			)
		)
		(pin "1"
		)
		(instances
			(project "data-center-rdimm-ddr5-tester"
				(path ""
					(reference "#PWR0241")
					(unit 1)
				)
			)
		)
	)
	(symbol
		(lib_id "antmicropower:GND")
		(at 191.77 151.13 0)
		(unit 1)
		(exclude_from_sim no)
		(in_bom yes)
		(on_board yes)
		(dnp no)
		(fields_autoplaced yes)
		(property "Reference" "#PWR0251"
			(at 191.77 157.48 0)
			(effects
				(font
					(size 1.27 1.27)
				)
				(hide yes)
			)
		)
		(property "Value" "GND"
			(at 189.865 155.575 0)
			(effects
				(font
					(size 1.27 1.27)
					(thickness 0.15)
				)
				(justify left bottom)
			)
		)
		(property "Footprint" ""
			(at 200.66 158.75 0)
			(effects
				(font
					(size 1.27 1.27)
					(thickness 0.15)
				)
				(justify left bottom)
				(hide yes)
			)
		)
		(property "Datasheet" ""
			(at 200.66 163.83 0)
			(effects
				(font
					(size 1.27 1.27)
					(thickness 0.15)
				)
				(justify left bottom)
				(hide yes)
			)
		)
		(property "Description" ""
			(at 191.77 151.13 0)
			(effects
				(font
					(size 1.27 1.27)
				)
				(hide yes)
			)
		)
		(property "Author" "Antmicro"
			(at 200.66 156.21 0)
			(effects
				(font
					(size 1.27 1.27)
					(thickness 0.15)
				)
				(justify left bottom)
				(hide yes)
			)
		)
		(property "License" "Apache-2.0"
			(at 200.66 158.75 0)
			(effects
				(font
					(size 1.27 1.27)
					(thickness 0.15)
				)
				(justify left bottom)
				(hide yes)
			)
		)
		(pin "1"
		)
		(instances
			(project "data-center-rdimm-ddr5-tester"
				(path ""
					(reference "#PWR0251")
					(unit 1)
				)
			)
		)
	)
	(symbol
		(lib_id "antmicropower:GND")
		(at 199.39 134.62 0)
		(unit 1)
		(exclude_from_sim no)
		(in_bom yes)
		(on_board yes)
		(dnp no)
		(fields_autoplaced yes)
		(property "Reference" "#PWR0243"
			(at 199.39 140.97 0)
			(effects
				(font
					(size 1.27 1.27)
				)
				(hide yes)
			)
		)
		(property "Value" "GND"
			(at 197.485 139.065 0)
			(effects
				(font
					(size 1.27 1.27)
					(thickness 0.15)
				)
				(justify left bottom)
			)
		)
		(property "Footprint" ""
			(at 208.28 142.24 0)
			(effects
				(font
					(size 1.27 1.27)
					(thickness 0.15)
				)
				(justify left bottom)
				(hide yes)
			)
		)
		(property "Datasheet" ""
			(at 208.28 147.32 0)
			(effects
				(font
					(size 1.27 1.27)
					(thickness 0.15)
				)
				(justify left bottom)
				(hide yes)
			)
		)
		(property "Description" ""
			(at 199.39 134.62 0)
			(effects
				(font
					(size 1.27 1.27)
				)
				(hide yes)
			)
		)
		(property "Author" "Antmicro"
			(at 208.28 139.7 0)
			(effects
				(font
					(size 1.27 1.27)
					(thickness 0.15)
				)
				(justify left bottom)
				(hide yes)
			)
		)
		(property "License" "Apache-2.0"
			(at 208.28 142.24 0)
			(effects
				(font
					(size 1.27 1.27)
					(thickness 0.15)
				)
				(justify left bottom)
				(hide yes)
			)
		)
		(pin "1"
		)
		(instances
			(project "data-center-rdimm-ddr5-tester"
				(path ""
					(reference "#PWR0243")
					(unit 1)
				)
			)
		)
	)
	(symbol
		(lib_id "antmicropower:GND")
		(at 297.18 95.25 0)
		(unit 1)
		(exclude_from_sim no)
		(in_bom yes)
		(on_board yes)
		(dnp no)
		(fields_autoplaced yes)
		(property "Reference" "#PWR0242"
			(at 297.18 101.6 0)
			(effects
				(font
					(size 1.27 1.27)
				)
				(hide yes)
			)
		)
		(property "Value" "GND"
			(at 295.275 99.695 0)
			(effects
				(font
					(size 1.27 1.27)
					(thickness 0.15)
				)
				(justify left bottom)
			)
		)
		(property "Footprint" ""
			(at 306.07 102.87 0)
			(effects
				(font
					(size 1.27 1.27)
					(thickness 0.15)
				)
				(justify left bottom)
				(hide yes)
			)
		)
		(property "Datasheet" ""
			(at 306.07 107.95 0)
			(effects
				(font
					(size 1.27 1.27)
					(thickness 0.15)
				)
				(justify left bottom)
				(hide yes)
			)
		)
		(property "Description" ""
			(at 297.18 95.25 0)
			(effects
				(font
					(size 1.27 1.27)
				)
				(hide yes)
			)
		)
		(property "Author" "Antmicro"
			(at 306.07 100.33 0)
			(effects
				(font
					(size 1.27 1.27)
					(thickness 0.15)
				)
				(justify left bottom)
				(hide yes)
			)
		)
		(property "License" "Apache-2.0"
			(at 306.07 102.87 0)
			(effects
				(font
					(size 1.27 1.27)
					(thickness 0.15)
				)
				(justify left bottom)
				(hide yes)
			)
		)
		(pin "1"
		)
		(instances
			(project "data-center-rdimm-ddr5-tester"
				(path ""
					(reference "#PWR0242")
					(unit 1)
				)
			)
		)
	)
	(symbol
		(lib_id "antmicroResistors0402:R_220R_0402")
		(at 347.98 53.34 0)
		(mirror x)
		(unit 1)
		(exclude_from_sim no)
		(in_bom yes)
		(on_board yes)
		(dnp no)
		(fields_autoplaced yes)
		(property "Reference" "R98"
			(at 350.52 46.99 0)
			(effects
				(font
					(size 1.27 1.27)
				)
			)
		)
		(property "Value" "R_220R_0402"
			(at 368.3 40.64 0)
			(effects
				(font
					(size 1.27 1.27)
					(thickness 0.15)
				)
				(justify left bottom)
				(hide yes)
			)
		)
		(property "Footprint" "antmicro-footprints:R_0402_1005Metric"
			(at 368.3 38.1 0)
			(effects
				(font
					(size 1.27 1.27)
					(thickness 0.15)
				)
				(justify left bottom)
				(hide yes)
			)
		)
		(property "Datasheet" "https://www.bourns.com/docs/product-datasheets/cr.pdf"
			(at 368.3 35.56 0)
			(effects
				(font
					(size 1.27 1.27)
					(thickness 0.15)
				)
				(justify left bottom)
				(hide yes)
			)
		)
		(property "Description" ""
			(at 347.98 53.34 0)
			(effects
				(font
					(size 1.27 1.27)
				)
				(hide yes)
			)
		)
		(property "Manufacturer" "Bourns"
			(at 368.3 30.48 0)
			(effects
				(font
					(size 1.27 1.27)
					(thickness 0.15)
				)
				(justify left bottom)
				(hide yes)
			)
		)
		(property "MPN" "CR0402-FX-2200GLF"
			(at 368.3 33.02 0)
			(effects
				(font
					(size 1.27 1.27)
					(thickness 0.15)
				)
				(justify left bottom)
				(hide yes)
			)
		)
		(property "Val" "220R"
			(at 350.52 49.53 0)
			(effects
				(font
					(size 1.27 1.27)
					(thickness 0.15)
				)
			)
		)
		(property "License" "Apache-2.0"
			(at 368.3 27.94 0)
			(effects
				(font
					(size 1.27 1.27)
					(thickness 0.15)
				)
				(justify left bottom)
				(hide yes)
			)
		)
		(property "Author" "Antmicro"
			(at 368.3 25.4 0)
			(effects
				(font
					(size 1.27 1.27)
					(thickness 0.15)
				)
				(justify left bottom)
				(hide yes)
			)
		)
		(property "Tolerance" "1%"
			(at 368.3 43.18 0)
			(effects
				(font
					(size 1.27 1.27)
				)
				(justify left bottom)
				(hide yes)
			)
		)
		(pin "1"
		)
		(pin "2"
		)
		(instances
			(project "data-center-rdimm-ddr5-tester"
				(path ""
					(reference "R98")
					(unit 1)
				)
			)
		)
	)
	(symbol
		(lib_id "antmicroResistors0402:R_220R_0402")
		(at 347.98 78.74 0)
		(mirror x)
		(unit 1)
		(exclude_from_sim no)
		(in_bom yes)
		(on_board yes)
		(dnp no)
		(fields_autoplaced yes)
		(property "Reference" "R99"
			(at 350.52 72.39 0)
			(effects
				(font
					(size 1.27 1.27)
				)
			)
		)
		(property "Value" "R_220R_0402"
			(at 368.3 66.04 0)
			(effects
				(font
					(size 1.27 1.27)
					(thickness 0.15)
				)
				(justify left bottom)
				(hide yes)
			)
		)
		(property "Footprint" "antmicro-footprints:R_0402_1005Metric"
			(at 368.3 63.5 0)
			(effects
				(font
					(size 1.27 1.27)
					(thickness 0.15)
				)
				(justify left bottom)
				(hide yes)
			)
		)
		(property "Datasheet" "https://www.bourns.com/docs/product-datasheets/cr.pdf"
			(at 368.3 60.96 0)
			(effects
				(font
					(size 1.27 1.27)
					(thickness 0.15)
				)
				(justify left bottom)
				(hide yes)
			)
		)
		(property "Description" ""
			(at 347.98 78.74 0)
			(effects
				(font
					(size 1.27 1.27)
				)
				(hide yes)
			)
		)
		(property "Manufacturer" "Bourns"
			(at 368.3 55.88 0)
			(effects
				(font
					(size 1.27 1.27)
					(thickness 0.15)
				)
				(justify left bottom)
				(hide yes)
			)
		)
		(property "MPN" "CR0402-FX-2200GLF"
			(at 368.3 58.42 0)
			(effects
				(font
					(size 1.27 1.27)
					(thickness 0.15)
				)
				(justify left bottom)
				(hide yes)
			)
		)
		(property "Val" "220R"
			(at 350.52 74.93 0)
			(effects
				(font
					(size 1.27 1.27)
					(thickness 0.15)
				)
			)
		)
		(property "License" "Apache-2.0"
			(at 368.3 53.34 0)
			(effects
				(font
					(size 1.27 1.27)
					(thickness 0.15)
				)
				(justify left bottom)
				(hide yes)
			)
		)
		(property "Author" "Antmicro"
			(at 368.3 50.8 0)
			(effects
				(font
					(size 1.27 1.27)
					(thickness 0.15)
				)
				(justify left bottom)
				(hide yes)
			)
		)
		(property "Tolerance" "1%"
			(at 368.3 68.58 0)
			(effects
				(font
					(size 1.27 1.27)
				)
				(justify left bottom)
				(hide yes)
			)
		)
		(pin "1"
		)
		(pin "2"
		)
		(instances
			(project "data-center-rdimm-ddr5-tester"
				(path ""
					(reference "R99")
					(unit 1)
				)
			)
		)
	)
	(symbol
		(lib_id "antmicroResistors0402:R_1k_0402")
		(at 71.12 149.86 180)
		(unit 1)
		(exclude_from_sim no)
		(in_bom yes)
		(on_board yes)
		(dnp no)
		(property "Reference" "R110"
			(at 74.93 151.13 0)
			(effects
				(font
					(size 1.27 1.27)
				)
			)
		)
		(property "Value" "R_1k_0402"
			(at 50.8 137.16 0)
			(effects
				(font
					(size 1.27 1.27)
					(thickness 0.15)
				)
				(justify left bottom)
				(hide yes)
			)
		)
		(property "Footprint" "antmicro-footprints:R_0402_1005Metric"
			(at 50.8 134.62 0)
			(effects
				(font
					(size 1.27 1.27)
					(thickness 0.15)
				)
				(justify left bottom)
				(hide yes)
			)
		)
		(property "Datasheet" "https://www.bourns.com/docs/product-datasheets/cr.pdf"
			(at 50.8 132.08 0)
			(effects
				(font
					(size 1.27 1.27)
					(thickness 0.15)
				)
				(justify left bottom)
				(hide yes)
			)
		)
		(property "Description" ""
			(at 71.12 149.86 0)
			(effects
				(font
					(size 1.27 1.27)
				)
				(hide yes)
			)
		)
		(property "Manufacturer" "Bourns"
			(at 50.8 127 0)
			(effects
				(font
					(size 1.27 1.27)
					(thickness 0.15)
				)
				(justify left bottom)
				(hide yes)
			)
		)
		(property "MPN" "CR0402-FX-1001GLF"
			(at 50.8 129.54 0)
			(effects
				(font
					(size 1.27 1.27)
					(thickness 0.15)
				)
				(justify left bottom)
				(hide yes)
			)
		)
		(property "Val" "1k"
			(at 64.135 151.13 0)
			(effects
				(font
					(size 1.27 1.27)
					(thickness 0.15)
				)
			)
		)
		(property "License" "Apache-2.0"
			(at 50.8 124.46 0)
			(effects
				(font
					(size 1.27 1.27)
					(thickness 0.15)
				)
				(justify left bottom)
				(hide yes)
			)
		)
		(property "Author" "Antmicro"
			(at 50.8 121.92 0)
			(effects
				(font
					(size 1.27 1.27)
					(thickness 0.15)
				)
				(justify left bottom)
				(hide yes)
			)
		)
		(property "Tolerance" "1%"
			(at 50.8 139.7 0)
			(effects
				(font
					(size 1.27 1.27)
				)
				(justify left bottom)
				(hide yes)
			)
		)
		(pin "1"
		)
		(pin "2"
		)
		(instances
			(project "data-center-rdimm-ddr5-tester"
				(path ""
					(reference "R110")
					(unit 1)
				)
			)
		)
	)
	(symbol
		(lib_id "antmicroResistors0402:R_2k2_0402")
		(at 356.87 168.91 0)
		(unit 1)
		(exclude_from_sim no)
		(in_bom yes)
		(on_board yes)
		(dnp no)
		(property "Reference" "R113"
			(at 353.695 167.64 0)
			(effects
				(font
					(size 1.27 1.27)
				)
			)
		)
		(property "Value" "R_2k2_0402"
			(at 377.19 181.61 0)
			(effects
				(font
					(size 1.27 1.27)
					(thickness 0.15)
				)
				(justify left bottom)
				(hide yes)
			)
		)
		(property "Footprint" "antmicro-footprints:R_0402_1005Metric"
			(at 377.19 184.15 0)
			(effects
				(font
					(size 1.27 1.27)
					(thickness 0.15)
				)
				(justify left bottom)
				(hide yes)
			)
		)
		(property "Datasheet" "https://www.bourns.com/docs/product-datasheets/cr.pdf"
			(at 377.19 186.69 0)
			(effects
				(font
					(size 1.27 1.27)
					(thickness 0.15)
				)
				(justify left bottom)
				(hide yes)
			)
		)
		(property "Description" ""
			(at 356.87 168.91 0)
			(effects
				(font
					(size 1.27 1.27)
				)
				(hide yes)
			)
		)
		(property "Manufacturer" "Bourns"
			(at 377.19 191.77 0)
			(effects
				(font
					(size 1.27 1.27)
					(thickness 0.15)
				)
				(justify left bottom)
				(hide yes)
			)
		)
		(property "MPN" "CR0402-FX-2201GLF"
			(at 377.19 189.23 0)
			(effects
				(font
					(size 1.27 1.27)
					(thickness 0.15)
				)
				(justify left bottom)
				(hide yes)
			)
		)
		(property "Val" "2k2"
			(at 364.49 167.64 0)
			(effects
				(font
					(size 1.27 1.27)
					(thickness 0.15)
				)
			)
		)
		(property "License" "Apache-2.0"
			(at 377.19 194.31 0)
			(effects
				(font
					(size 1.27 1.27)
					(thickness 0.15)
				)
				(justify left bottom)
				(hide yes)
			)
		)
		(property "Author" "Antmicro"
			(at 377.19 196.85 0)
			(effects
				(font
					(size 1.27 1.27)
					(thickness 0.15)
				)
				(justify left bottom)
				(hide yes)
			)
		)
		(property "Tolerance" "1%"
			(at 377.19 179.07 0)
			(effects
				(font
					(size 1.27 1.27)
				)
				(justify left bottom)
				(hide yes)
			)
		)
		(pin "1"
		)
		(pin "2"
		)
		(instances
			(project "data-center-rdimm-ddr5-tester"
				(path ""
					(reference "R113")
					(unit 1)
				)
			)
		)
	)
	(symbol
		(lib_id "antmicroResistors0402:R_2k2_0402")
		(at 356.87 166.37 0)
		(unit 1)
		(exclude_from_sim no)
		(in_bom yes)
		(on_board yes)
		(dnp no)
		(property "Reference" "R114"
			(at 353.695 165.1 0)
			(effects
				(font
					(size 1.27 1.27)
				)
			)
		)
		(property "Value" "R_2k2_0402"
			(at 377.19 179.07 0)
			(effects
				(font
					(size 1.27 1.27)
					(thickness 0.15)
				)
				(justify left bottom)
				(hide yes)
			)
		)
		(property "Footprint" "antmicro-footprints:R_0402_1005Metric"
			(at 377.19 181.61 0)
			(effects
				(font
					(size 1.27 1.27)
					(thickness 0.15)
				)
				(justify left bottom)
				(hide yes)
			)
		)
		(property "Datasheet" "https://www.bourns.com/docs/product-datasheets/cr.pdf"
			(at 377.19 184.15 0)
			(effects
				(font
					(size 1.27 1.27)
					(thickness 0.15)
				)
				(justify left bottom)
				(hide yes)
			)
		)
		(property "Description" ""
			(at 356.87 166.37 0)
			(effects
				(font
					(size 1.27 1.27)
				)
				(hide yes)
			)
		)
		(property "Manufacturer" "Bourns"
			(at 377.19 189.23 0)
			(effects
				(font
					(size 1.27 1.27)
					(thickness 0.15)
				)
				(justify left bottom)
				(hide yes)
			)
		)
		(property "MPN" "CR0402-FX-2201GLF"
			(at 377.19 186.69 0)
			(effects
				(font
					(size 1.27 1.27)
					(thickness 0.15)
				)
				(justify left bottom)
				(hide yes)
			)
		)
		(property "Val" "2k2"
			(at 364.49 165.1 0)
			(effects
				(font
					(size 1.27 1.27)
					(thickness 0.15)
				)
			)
		)
		(property "License" "Apache-2.0"
			(at 377.19 191.77 0)
			(effects
				(font
					(size 1.27 1.27)
					(thickness 0.15)
				)
				(justify left bottom)
				(hide yes)
			)
		)
		(property "Author" "Antmicro"
			(at 377.19 194.31 0)
			(effects
				(font
					(size 1.27 1.27)
					(thickness 0.15)
				)
				(justify left bottom)
				(hide yes)
			)
		)
		(property "Tolerance" "1%"
			(at 377.19 176.53 0)
			(effects
				(font
					(size 1.27 1.27)
				)
				(justify left bottom)
				(hide yes)
			)
		)
		(pin "1"
		)
		(pin "2"
		)
		(instances
			(project "data-center-rdimm-ddr5-tester"
				(path ""
					(reference "R114")
					(unit 1)
				)
			)
		)
	)
	(symbol
		(lib_id "antmicroResistors0402:R_2k2_0402")
		(at 356.87 163.83 0)
		(unit 1)
		(exclude_from_sim no)
		(in_bom no)
		(on_board yes)
		(dnp yes)
		(property "Reference" "R115"
			(at 353.695 162.56 0)
			(effects
				(font
					(size 1.27 1.27)
				)
			)
		)
		(property "Value" "R_2k2_0402"
			(at 377.19 176.53 0)
			(effects
				(font
					(size 1.27 1.27)
					(thickness 0.15)
				)
				(justify left bottom)
				(hide yes)
			)
		)
		(property "Footprint" "antmicro-footprints:R_0402_1005Metric"
			(at 377.19 179.07 0)
			(effects
				(font
					(size 1.27 1.27)
					(thickness 0.15)
				)
				(justify left bottom)
				(hide yes)
			)
		)
		(property "Datasheet" "https://www.bourns.com/docs/product-datasheets/cr.pdf"
			(at 377.19 181.61 0)
			(effects
				(font
					(size 1.27 1.27)
					(thickness 0.15)
				)
				(justify left bottom)
				(hide yes)
			)
		)
		(property "Description" ""
			(at 356.87 163.83 0)
			(effects
				(font
					(size 1.27 1.27)
				)
				(hide yes)
			)
		)
		(property "Manufacturer" "Bourns"
			(at 377.19 186.69 0)
			(effects
				(font
					(size 1.27 1.27)
					(thickness 0.15)
				)
				(justify left bottom)
				(hide yes)
			)
		)
		(property "MPN" "CR0402-FX-2201GLF"
			(at 377.19 184.15 0)
			(effects
				(font
					(size 1.27 1.27)
					(thickness 0.15)
				)
				(justify left bottom)
				(hide yes)
			)
		)
		(property "Val" "2k2"
			(at 364.49 162.56 0)
			(effects
				(font
					(size 1.27 1.27)
					(thickness 0.15)
				)
			)
		)
		(property "License" "Apache-2.0"
			(at 377.19 189.23 0)
			(effects
				(font
					(size 1.27 1.27)
					(thickness 0.15)
				)
				(justify left bottom)
				(hide yes)
			)
		)
		(property "Author" "Antmicro"
			(at 377.19 191.77 0)
			(effects
				(font
					(size 1.27 1.27)
					(thickness 0.15)
				)
				(justify left bottom)
				(hide yes)
			)
		)
		(property "Tolerance" "1%"
			(at 377.19 173.99 0)
			(effects
				(font
					(size 1.27 1.27)
				)
				(justify left bottom)
				(hide yes)
			)
		)
		(pin "1"
		)
		(pin "2"
		)
		(instances
			(project "data-center-rdimm-ddr5-tester"
				(path ""
					(reference "R115")
					(unit 1)
				)
			)
		)
	)
	(symbol
		(lib_id "antmicroResistors0402:R_2k2_0402")
		(at 356.87 161.29 0)
		(unit 1)
		(exclude_from_sim no)
		(in_bom no)
		(on_board yes)
		(dnp yes)
		(property "Reference" "R116"
			(at 353.695 160.02 0)
			(effects
				(font
					(size 1.27 1.27)
				)
			)
		)
		(property "Value" "R_2k2_0402"
			(at 377.19 173.99 0)
			(effects
				(font
					(size 1.27 1.27)
					(thickness 0.15)
				)
				(justify left bottom)
				(hide yes)
			)
		)
		(property "Footprint" "antmicro-footprints:R_0402_1005Metric"
			(at 377.19 176.53 0)
			(effects
				(font
					(size 1.27 1.27)
					(thickness 0.15)
				)
				(justify left bottom)
				(hide yes)
			)
		)
		(property "Datasheet" "https://www.bourns.com/docs/product-datasheets/cr.pdf"
			(at 377.19 179.07 0)
			(effects
				(font
					(size 1.27 1.27)
					(thickness 0.15)
				)
				(justify left bottom)
				(hide yes)
			)
		)
		(property "Description" ""
			(at 356.87 161.29 0)
			(effects
				(font
					(size 1.27 1.27)
				)
				(hide yes)
			)
		)
		(property "Manufacturer" "Bourns"
			(at 377.19 184.15 0)
			(effects
				(font
					(size 1.27 1.27)
					(thickness 0.15)
				)
				(justify left bottom)
				(hide yes)
			)
		)
		(property "MPN" "CR0402-FX-2201GLF"
			(at 377.19 181.61 0)
			(effects
				(font
					(size 1.27 1.27)
					(thickness 0.15)
				)
				(justify left bottom)
				(hide yes)
			)
		)
		(property "Val" "2k2"
			(at 364.49 160.02 0)
			(effects
				(font
					(size 1.27 1.27)
					(thickness 0.15)
				)
			)
		)
		(property "License" "Apache-2.0"
			(at 377.19 186.69 0)
			(effects
				(font
					(size 1.27 1.27)
					(thickness 0.15)
				)
				(justify left bottom)
				(hide yes)
			)
		)
		(property "Author" "Antmicro"
			(at 377.19 189.23 0)
			(effects
				(font
					(size 1.27 1.27)
					(thickness 0.15)
				)
				(justify left bottom)
				(hide yes)
			)
		)
		(property "Tolerance" "1%"
			(at 377.19 171.45 0)
			(effects
				(font
					(size 1.27 1.27)
				)
				(justify left bottom)
				(hide yes)
			)
		)
		(pin "1"
		)
		(pin "2"
		)
		(instances
			(project "data-center-rdimm-ddr5-tester"
				(path ""
					(reference "R116")
					(unit 1)
				)
			)
		)
	)
	(symbol
		(lib_id "antmicroResistors0402:R_2k2_0402")
		(at 356.87 180.34 0)
		(unit 1)
		(exclude_from_sim no)
		(in_bom yes)
		(on_board yes)
		(dnp no)
		(property "Reference" "R117"
			(at 353.695 179.07 0)
			(effects
				(font
					(size 1.27 1.27)
				)
			)
		)
		(property "Value" "R_2k2_0402"
			(at 377.19 193.04 0)
			(effects
				(font
					(size 1.27 1.27)
					(thickness 0.15)
				)
				(justify left bottom)
				(hide yes)
			)
		)
		(property "Footprint" "antmicro-footprints:R_0402_1005Metric"
			(at 377.19 195.58 0)
			(effects
				(font
					(size 1.27 1.27)
					(thickness 0.15)
				)
				(justify left bottom)
				(hide yes)
			)
		)
		(property "Datasheet" "https://www.bourns.com/docs/product-datasheets/cr.pdf"
			(at 377.19 198.12 0)
			(effects
				(font
					(size 1.27 1.27)
					(thickness 0.15)
				)
				(justify left bottom)
				(hide yes)
			)
		)
		(property "Description" ""
			(at 356.87 180.34 0)
			(effects
				(font
					(size 1.27 1.27)
				)
				(hide yes)
			)
		)
		(property "Manufacturer" "Bourns"
			(at 377.19 203.2 0)
			(effects
				(font
					(size 1.27 1.27)
					(thickness 0.15)
				)
				(justify left bottom)
				(hide yes)
			)
		)
		(property "MPN" "CR0402-FX-2201GLF"
			(at 377.19 200.66 0)
			(effects
				(font
					(size 1.27 1.27)
					(thickness 0.15)
				)
				(justify left bottom)
				(hide yes)
			)
		)
		(property "Val" "2k2"
			(at 364.49 179.07 0)
			(effects
				(font
					(size 1.27 1.27)
					(thickness 0.15)
				)
			)
		)
		(property "License" "Apache-2.0"
			(at 377.19 205.74 0)
			(effects
				(font
					(size 1.27 1.27)
					(thickness 0.15)
				)
				(justify left bottom)
				(hide yes)
			)
		)
		(property "Author" "Antmicro"
			(at 377.19 208.28 0)
			(effects
				(font
					(size 1.27 1.27)
					(thickness 0.15)
				)
				(justify left bottom)
				(hide yes)
			)
		)
		(property "Tolerance" "1%"
			(at 377.19 190.5 0)
			(effects
				(font
					(size 1.27 1.27)
				)
				(justify left bottom)
				(hide yes)
			)
		)
		(pin "1"
		)
		(pin "2"
		)
		(instances
			(project "data-center-rdimm-ddr5-tester"
				(path ""
					(reference "R117")
					(unit 1)
				)
			)
		)
	)
	(symbol
		(lib_id "antmicroResistors0402:R_2k2_0402")
		(at 356.87 171.45 0)
		(unit 1)
		(exclude_from_sim no)
		(in_bom yes)
		(on_board yes)
		(dnp no)
		(property "Reference" "R118"
			(at 353.695 170.18 0)
			(effects
				(font
					(size 1.27 1.27)
				)
			)
		)
		(property "Value" "R_2k2_0402"
			(at 377.19 184.15 0)
			(effects
				(font
					(size 1.27 1.27)
					(thickness 0.15)
				)
				(justify left bottom)
				(hide yes)
			)
		)
		(property "Footprint" "antmicro-footprints:R_0402_1005Metric"
			(at 377.19 186.69 0)
			(effects
				(font
					(size 1.27 1.27)
					(thickness 0.15)
				)
				(justify left bottom)
				(hide yes)
			)
		)
		(property "Datasheet" "https://www.bourns.com/docs/product-datasheets/cr.pdf"
			(at 377.19 189.23 0)
			(effects
				(font
					(size 1.27 1.27)
					(thickness 0.15)
				)
				(justify left bottom)
				(hide yes)
			)
		)
		(property "Description" ""
			(at 356.87 171.45 0)
			(effects
				(font
					(size 1.27 1.27)
				)
				(hide yes)
			)
		)
		(property "Manufacturer" "Bourns"
			(at 377.19 194.31 0)
			(effects
				(font
					(size 1.27 1.27)
					(thickness 0.15)
				)
				(justify left bottom)
				(hide yes)
			)
		)
		(property "MPN" "CR0402-FX-2201GLF"
			(at 377.19 191.77 0)
			(effects
				(font
					(size 1.27 1.27)
					(thickness 0.15)
				)
				(justify left bottom)
				(hide yes)
			)
		)
		(property "Val" "2k2"
			(at 364.49 170.18 0)
			(effects
				(font
					(size 1.27 1.27)
					(thickness 0.15)
				)
			)
		)
		(property "License" "Apache-2.0"
			(at 377.19 196.85 0)
			(effects
				(font
					(size 1.27 1.27)
					(thickness 0.15)
				)
				(justify left bottom)
				(hide yes)
			)
		)
		(property "Author" "Antmicro"
			(at 377.19 199.39 0)
			(effects
				(font
					(size 1.27 1.27)
					(thickness 0.15)
				)
				(justify left bottom)
				(hide yes)
			)
		)
		(property "Tolerance" "1%"
			(at 377.19 181.61 0)
			(effects
				(font
					(size 1.27 1.27)
				)
				(justify left bottom)
				(hide yes)
			)
		)
		(pin "1"
		)
		(pin "2"
		)
		(instances
			(project "data-center-rdimm-ddr5-tester"
				(path ""
					(reference "R118")
					(unit 1)
				)
			)
		)
	)
	(symbol
		(lib_id "antmicroResistors0402:R_2k2_0402")
		(at 356.87 173.99 0)
		(unit 1)
		(exclude_from_sim no)
		(in_bom no)
		(on_board yes)
		(dnp yes)
		(property "Reference" "R120"
			(at 353.695 172.72 0)
			(effects
				(font
					(size 1.27 1.27)
				)
			)
		)
		(property "Value" "R_2k2_0402"
			(at 377.19 186.69 0)
			(effects
				(font
					(size 1.27 1.27)
					(thickness 0.15)
				)
				(justify left bottom)
				(hide yes)
			)
		)
		(property "Footprint" "antmicro-footprints:R_0402_1005Metric"
			(at 377.19 189.23 0)
			(effects
				(font
					(size 1.27 1.27)
					(thickness 0.15)
				)
				(justify left bottom)
				(hide yes)
			)
		)
		(property "Datasheet" "https://www.bourns.com/docs/product-datasheets/cr.pdf"
			(at 377.19 191.77 0)
			(effects
				(font
					(size 1.27 1.27)
					(thickness 0.15)
				)
				(justify left bottom)
				(hide yes)
			)
		)
		(property "Description" ""
			(at 356.87 173.99 0)
			(effects
				(font
					(size 1.27 1.27)
				)
				(hide yes)
			)
		)
		(property "Manufacturer" "Bourns"
			(at 377.19 196.85 0)
			(effects
				(font
					(size 1.27 1.27)
					(thickness 0.15)
				)
				(justify left bottom)
				(hide yes)
			)
		)
		(property "MPN" "CR0402-FX-2201GLF"
			(at 377.19 194.31 0)
			(effects
				(font
					(size 1.27 1.27)
					(thickness 0.15)
				)
				(justify left bottom)
				(hide yes)
			)
		)
		(property "Val" "2k2"
			(at 364.49 172.72 0)
			(effects
				(font
					(size 1.27 1.27)
					(thickness 0.15)
				)
			)
		)
		(property "License" "Apache-2.0"
			(at 377.19 199.39 0)
			(effects
				(font
					(size 1.27 1.27)
					(thickness 0.15)
				)
				(justify left bottom)
				(hide yes)
			)
		)
		(property "Author" "Antmicro"
			(at 377.19 201.93 0)
			(effects
				(font
					(size 1.27 1.27)
					(thickness 0.15)
				)
				(justify left bottom)
				(hide yes)
			)
		)
		(property "Tolerance" "1%"
			(at 377.19 184.15 0)
			(effects
				(font
					(size 1.27 1.27)
				)
				(justify left bottom)
				(hide yes)
			)
		)
		(pin "1"
		)
		(pin "2"
		)
		(instances
			(project "data-center-rdimm-ddr5-tester"
				(path ""
					(reference "R120")
					(unit 1)
				)
			)
		)
	)
	(symbol
		(lib_id "antmicroResistors0402:R_2k2_0402")
		(at 356.87 176.53 0)
		(unit 1)
		(exclude_from_sim no)
		(in_bom no)
		(on_board yes)
		(dnp yes)
		(property "Reference" "R121"
			(at 353.695 175.26 0)
			(effects
				(font
					(size 1.27 1.27)
				)
			)
		)
		(property "Value" "R_2k2_0402"
			(at 377.19 189.23 0)
			(effects
				(font
					(size 1.27 1.27)
					(thickness 0.15)
				)
				(justify left bottom)
				(hide yes)
			)
		)
		(property "Footprint" "antmicro-footprints:R_0402_1005Metric"
			(at 377.19 191.77 0)
			(effects
				(font
					(size 1.27 1.27)
					(thickness 0.15)
				)
				(justify left bottom)
				(hide yes)
			)
		)
		(property "Datasheet" "https://www.bourns.com/docs/product-datasheets/cr.pdf"
			(at 377.19 194.31 0)
			(effects
				(font
					(size 1.27 1.27)
					(thickness 0.15)
				)
				(justify left bottom)
				(hide yes)
			)
		)
		(property "Description" ""
			(at 356.87 176.53 0)
			(effects
				(font
					(size 1.27 1.27)
				)
				(hide yes)
			)
		)
		(property "Manufacturer" "Bourns"
			(at 377.19 199.39 0)
			(effects
				(font
					(size 1.27 1.27)
					(thickness 0.15)
				)
				(justify left bottom)
				(hide yes)
			)
		)
		(property "MPN" "CR0402-FX-2201GLF"
			(at 377.19 196.85 0)
			(effects
				(font
					(size 1.27 1.27)
					(thickness 0.15)
				)
				(justify left bottom)
				(hide yes)
			)
		)
		(property "Val" "2k2"
			(at 364.49 175.26 0)
			(effects
				(font
					(size 1.27 1.27)
					(thickness 0.15)
				)
			)
		)
		(property "License" "Apache-2.0"
			(at 377.19 201.93 0)
			(effects
				(font
					(size 1.27 1.27)
					(thickness 0.15)
				)
				(justify left bottom)
				(hide yes)
			)
		)
		(property "Author" "Antmicro"
			(at 377.19 204.47 0)
			(effects
				(font
					(size 1.27 1.27)
					(thickness 0.15)
				)
				(justify left bottom)
				(hide yes)
			)
		)
		(property "Tolerance" "1%"
			(at 377.19 186.69 0)
			(effects
				(font
					(size 1.27 1.27)
				)
				(justify left bottom)
				(hide yes)
			)
		)
		(pin "1"
		)
		(pin "2"
		)
		(instances
			(project "data-center-rdimm-ddr5-tester"
				(path ""
					(reference "R121")
					(unit 1)
				)
			)
		)
	)
	(symbol
		(lib_id "antmicroResistors0402:R_2k2_0402")
		(at 356.87 182.88 0)
		(unit 1)
		(exclude_from_sim no)
		(in_bom no)
		(on_board yes)
		(dnp yes)
		(property "Reference" "R119"
			(at 353.695 181.61 0)
			(effects
				(font
					(size 1.27 1.27)
				)
			)
		)
		(property "Value" "R_2k2_0402"
			(at 377.19 195.58 0)
			(effects
				(font
					(size 1.27 1.27)
					(thickness 0.15)
				)
				(justify left bottom)
				(hide yes)
			)
		)
		(property "Footprint" "antmicro-footprints:R_0402_1005Metric"
			(at 377.19 198.12 0)
			(effects
				(font
					(size 1.27 1.27)
					(thickness 0.15)
				)
				(justify left bottom)
				(hide yes)
			)
		)
		(property "Datasheet" "https://www.bourns.com/docs/product-datasheets/cr.pdf"
			(at 377.19 200.66 0)
			(effects
				(font
					(size 1.27 1.27)
					(thickness 0.15)
				)
				(justify left bottom)
				(hide yes)
			)
		)
		(property "Description" ""
			(at 356.87 182.88 0)
			(effects
				(font
					(size 1.27 1.27)
				)
				(hide yes)
			)
		)
		(property "Manufacturer" "Bourns"
			(at 377.19 205.74 0)
			(effects
				(font
					(size 1.27 1.27)
					(thickness 0.15)
				)
				(justify left bottom)
				(hide yes)
			)
		)
		(property "MPN" "CR0402-FX-2201GLF"
			(at 377.19 203.2 0)
			(effects
				(font
					(size 1.27 1.27)
					(thickness 0.15)
				)
				(justify left bottom)
				(hide yes)
			)
		)
		(property "Val" "2k2"
			(at 364.49 181.61 0)
			(effects
				(font
					(size 1.27 1.27)
					(thickness 0.15)
				)
			)
		)
		(property "License" "Apache-2.0"
			(at 377.19 208.28 0)
			(effects
				(font
					(size 1.27 1.27)
					(thickness 0.15)
				)
				(justify left bottom)
				(hide yes)
			)
		)
		(property "Author" "Antmicro"
			(at 377.19 210.82 0)
			(effects
				(font
					(size 1.27 1.27)
					(thickness 0.15)
				)
				(justify left bottom)
				(hide yes)
			)
		)
		(property "Tolerance" "1%"
			(at 377.19 193.04 0)
			(effects
				(font
					(size 1.27 1.27)
				)
				(justify left bottom)
				(hide yes)
			)
		)
		(pin "1"
		)
		(pin "2"
		)
		(instances
			(project "data-center-rdimm-ddr5-tester"
				(path ""
					(reference "R119")
					(unit 1)
				)
			)
		)
	)
	(symbol
		(lib_id "antmicropower:GND")
		(at 372.11 184.15 0)
		(unit 1)
		(exclude_from_sim no)
		(in_bom yes)
		(on_board yes)
		(dnp no)
		(property "Reference" "#PWR0261"
			(at 372.11 190.5 0)
			(effects
				(font
					(size 1.27 1.27)
				)
				(hide yes)
			)
		)
		(property "Value" "GND"
			(at 370.205 188.595 0)
			(effects
				(font
					(size 1.27 1.27)
					(thickness 0.15)
				)
				(justify left bottom)
			)
		)
		(property "Footprint" ""
			(at 381 191.77 0)
			(effects
				(font
					(size 1.27 1.27)
					(thickness 0.15)
				)
				(justify left bottom)
				(hide yes)
			)
		)
		(property "Datasheet" ""
			(at 381 196.85 0)
			(effects
				(font
					(size 1.27 1.27)
					(thickness 0.15)
				)
				(justify left bottom)
				(hide yes)
			)
		)
		(property "Description" ""
			(at 372.11 184.15 0)
			(effects
				(font
					(size 1.27 1.27)
				)
				(hide yes)
			)
		)
		(property "Author" "Antmicro"
			(at 381 189.23 0)
			(effects
				(font
					(size 1.27 1.27)
					(thickness 0.15)
				)
				(justify left bottom)
				(hide yes)
			)
		)
		(property "License" "Apache-2.0"
			(at 381 191.77 0)
			(effects
				(font
					(size 1.27 1.27)
					(thickness 0.15)
				)
				(justify left bottom)
				(hide yes)
			)
		)
		(pin "1"
		)
		(instances
			(project "data-center-rdimm-ddr5-tester"
				(path ""
					(reference "#PWR0261")
					(unit 1)
				)
			)
		)
	)
	(symbol
		(lib_id "antmicropower:+3V3")
		(at 361.95 52.07 0)
		(unit 1)
		(exclude_from_sim no)
		(in_bom yes)
		(on_board yes)
		(dnp no)
		(property "Reference" "#PWR0249"
			(at 361.95 55.88 0)
			(effects
				(font
					(size 1.27 1.27)
				)
				(hide yes)
			)
		)
		(property "Value" "+3V3"
			(at 358.775 49.53 0)
			(effects
				(font
					(size 1.27 1.27)
					(thickness 0.15)
				)
				(justify left bottom)
			)
		)
		(property "Footprint" ""
			(at 377.19 59.69 0)
			(effects
				(font
					(size 1.27 1.27)
					(thickness 0.15)
				)
				(justify left bottom)
				(hide yes)
			)
		)
		(property "Datasheet" ""
			(at 377.19 62.23 0)
			(effects
				(font
					(size 1.27 1.27)
					(thickness 0.15)
				)
				(justify left bottom)
				(hide yes)
			)
		)
		(property "Description" ""
			(at 361.95 52.07 0)
			(effects
				(font
					(size 1.27 1.27)
				)
				(hide yes)
			)
		)
		(property "Author" "Antmicro"
			(at 377.19 54.61 0)
			(effects
				(font
					(size 1.27 1.27)
					(thickness 0.15)
				)
				(justify left bottom)
				(hide yes)
			)
		)
		(property "License" "Apache-2.0"
			(at 377.19 57.15 0)
			(effects
				(font
					(size 1.27 1.27)
					(thickness 0.15)
				)
				(justify left bottom)
				(hide yes)
			)
		)
		(pin "1"
		)
		(instances
			(project "data-center-rdimm-ddr5-tester"
				(path ""
					(reference "#PWR0249")
					(unit 1)
				)
			)
		)
	)
	(symbol
		(lib_id "antmicroFerriteBeadsandChips:FB_120Z_2A_Murata-BLM18PG_0603")
		(at 242.57 142.24 0)
		(mirror y)
		(unit 1)
		(exclude_from_sim no)
		(in_bom yes)
		(on_board yes)
		(dnp no)
		(fields_autoplaced yes)
		(property "Reference" "FB6"
			(at 240.0681 136.845 0)
			(effects
				(font
					(size 1.27 1.27)
					(thickness 0.15)
				)
			)
		)
		(property "Value" "FB_120Z_2A_Murata-BLM18PG_0603"
			(at 227.33 144.78 0)
			(effects
				(font
					(size 1.27 1.27)
					(thickness 0.15)
				)
				(justify left bottom)
				(hide yes)
			)
		)
		(property "Footprint" "antmicro-footprints:FB_0603_1608Metric"
			(at 227.33 149.86 0)
			(effects
				(font
					(size 1.27 1.27)
					(thickness 0.15)
				)
				(justify left bottom)
				(hide yes)
			)
		)
		(property "Datasheet" "https://www.murata.com/en-us/products/productdata/8796738650142/ENFA0003.pdf"
			(at 227.33 152.4 0)
			(effects
				(font
					(size 1.27 1.27)
					(thickness 0.15)
				)
				(justify left bottom)
				(hide yes)
			)
		)
		(property "Description" ""
			(at 242.57 142.24 0)
			(effects
				(font
					(size 1.27 1.27)
				)
				(hide yes)
			)
		)
		(property "Val" "120Z/2A"
			(at 240.0681 139.3753 0)
			(effects
				(font
					(size 1.27 1.27)
				)
			)
		)
		(property "MPN" "BLM18PG121SN1D"
			(at 227.33 154.94 0)
			(effects
				(font
					(size 1.27 1.27)
					(thickness 0.15)
				)
				(justify left bottom)
				(hide yes)
			)
		)
		(property "Manufacturer" "Murata"
			(at 227.33 157.48 0)
			(effects
				(font
					(size 1.27 1.27)
					(thickness 0.15)
				)
				(justify left bottom)
				(hide yes)
			)
		)
		(property "Author" "Antmicro"
			(at 227.33 160.02 0)
			(effects
				(font
					(size 1.27 1.27)
					(thickness 0.15)
				)
				(justify left bottom)
				(hide yes)
			)
		)
		(property "License" "Apache-2.0"
			(at 227.33 162.56 0)
			(effects
				(font
					(size 1.27 1.27)
					(thickness 0.15)
				)
				(justify left bottom)
				(hide yes)
			)
		)
		(pin "1"
		)
		(pin "2"
		)
		(instances
			(project "data-center-rdimm-ddr5-tester"
				(path ""
					(reference "FB6")
					(unit 1)
				)
			)
		)
	)
	(symbol
		(lib_id "antmicroCapacitors0402:C_18p_0402")
		(at 86.36 208.28 90)
		(unit 1)
		(exclude_from_sim no)
		(in_bom yes)
		(on_board yes)
		(dnp no)
		(fields_autoplaced yes)
		(property "Reference" "C162"
			(at 84.036 204.903 90)
			(effects
				(font
					(size 1.27 1.27)
					(thickness 0.15)
				)
				(justify left)
			)
		)
		(property "Value" "C_18p_0402"
			(at 96.52 187.96 0)
			(effects
				(font
					(size 1.27 1.27)
					(thickness 0.15)
				)
				(justify left bottom)
				(hide yes)
			)
		)
		(property "Footprint" "antmicro-footprints:C_0402_1005Metric"
			(at 99.06 187.96 0)
			(effects
				(font
					(size 1.27 1.27)
					(thickness 0.15)
				)
				(justify left bottom)
				(hide yes)
			)
		)
		(property "Datasheet" "https://product.samsungsem.com/mlcc/CL05C180JB51PN.do"
			(at 101.6 187.96 0)
			(effects
				(font
					(size 1.27 1.27)
					(thickness 0.15)
				)
				(justify left bottom)
				(hide yes)
			)
		)
		(property "Description" ""
			(at 86.36 208.28 0)
			(effects
				(font
					(size 1.27 1.27)
				)
				(hide yes)
			)
		)
		(property "MPN" "CL05C180JB51PNC"
			(at 104.14 187.96 0)
			(effects
				(font
					(size 1.27 1.27)
					(thickness 0.15)
				)
				(justify left bottom)
				(hide yes)
			)
		)
		(property "Manufacturer" "Samsung Electro-Mechanics"
			(at 106.68 187.96 0)
			(effects
				(font
					(size 1.27 1.27)
					(thickness 0.15)
				)
				(justify left bottom)
				(hide yes)
			)
		)
		(property "License" "Apache-2.0"
			(at 109.22 187.96 0)
			(effects
				(font
					(size 1.27 1.27)
					(thickness 0.15)
				)
				(justify left bottom)
				(hide yes)
			)
		)
		(property "Author" "Antmicro"
			(at 111.76 187.96 0)
			(effects
				(font
					(size 1.27 1.27)
					(thickness 0.15)
				)
				(justify left bottom)
				(hide yes)
			)
		)
		(property "Val" "18p"
			(at 84.036 207.4267 90)
			(effects
				(font
					(size 1.27 1.27)
					(thickness 0.15)
				)
				(justify left)
			)
		)
		(property "Voltage" ""
			(at 114.3 187.96 0)
			(effects
				(font
					(size 1.27 1.27)
				)
				(justify left bottom)
				(hide yes)
			)
		)
		(property "Dielectric" ""
			(at 116.84 187.96 0)
			(effects
				(font
					(size 1.27 1.27)
				)
				(justify left bottom)
				(hide yes)
			)
		)
		(pin "1"
		)
		(pin "2"
		)
		(instances
			(project "data-center-rdimm-ddr5-tester"
				(path ""
					(reference "C162")
					(unit 1)
				)
			)
		)
	)
	(symbol
		(lib_id "antmicroCapacitors0402:C_100n_0402")
		(at 297.18 90.17 90)
		(unit 1)
		(exclude_from_sim no)
		(in_bom yes)
		(on_board yes)
		(dnp no)
		(fields_autoplaced yes)
		(property "Reference" "C135"
			(at 294.856 86.793 90)
			(effects
				(font
					(size 1.27 1.27)
					(thickness 0.15)
				)
				(justify left)
			)
		)
		(property "Value" "C_100n_0402"
			(at 307.34 69.85 0)
			(effects
				(font
					(size 1.27 1.27)
					(thickness 0.15)
				)
				(justify left bottom)
				(hide yes)
			)
		)
		(property "Footprint" "antmicro-footprints:C_0402_1005Metric"
			(at 309.88 69.85 0)
			(effects
				(font
					(size 1.27 1.27)
					(thickness 0.15)
				)
				(justify left bottom)
				(hide yes)
			)
		)
		(property "Datasheet" "https://www.murata.com/products/productdetail?partno=GRM155R61H104KE14%23"
			(at 312.42 69.85 0)
			(effects
				(font
					(size 1.27 1.27)
					(thickness 0.15)
				)
				(justify left bottom)
				(hide yes)
			)
		)
		(property "Description" ""
			(at 297.18 90.17 0)
			(effects
				(font
					(size 1.27 1.27)
				)
				(hide yes)
			)
		)
		(property "MPN" "GRM155R61H104KE14D"
			(at 314.96 69.85 0)
			(effects
				(font
					(size 1.27 1.27)
					(thickness 0.15)
				)
				(justify left bottom)
				(hide yes)
			)
		)
		(property "Manufacturer" "Murata"
			(at 317.5 69.85 0)
			(effects
				(font
					(size 1.27 1.27)
					(thickness 0.15)
				)
				(justify left bottom)
				(hide yes)
			)
		)
		(property "License" "Apache-2.0"
			(at 320.04 69.85 0)
			(effects
				(font
					(size 1.27 1.27)
					(thickness 0.15)
				)
				(justify left bottom)
				(hide yes)
			)
		)
		(property "Author" "Antmicro"
			(at 322.58 69.85 0)
			(effects
				(font
					(size 1.27 1.27)
					(thickness 0.15)
				)
				(justify left bottom)
				(hide yes)
			)
		)
		(property "Val" "100n"
			(at 294.856 89.3167 90)
			(effects
				(font
					(size 1.27 1.27)
					(thickness 0.15)
				)
				(justify left)
			)
		)
		(property "Voltage" "50V"
			(at 325.12 69.85 0)
			(effects
				(font
					(size 1.27 1.27)
				)
				(justify left bottom)
				(hide yes)
			)
		)
		(property "Dielectric" "X5R"
			(at 327.66 69.85 0)
			(effects
				(font
					(size 1.27 1.27)
				)
				(justify left bottom)
				(hide yes)
			)
		)
		(pin "1"
		)
		(pin "2"
		)
		(instances
			(project "data-center-rdimm-ddr5-tester"
				(path ""
					(reference "C135")
					(unit 1)
				)
			)
		)
	)
	(symbol
		(lib_id "antmicroCapacitors0402:C_100n_0402")
		(at 300.99 90.17 90)
		(unit 1)
		(exclude_from_sim no)
		(in_bom yes)
		(on_board yes)
		(dnp no)
		(fields_autoplaced yes)
		(property "Reference" "C137"
			(at 303.3141 86.793 90)
			(effects
				(font
					(size 1.27 1.27)
					(thickness 0.15)
				)
				(justify right)
			)
		)
		(property "Value" "C_100n_0402"
			(at 311.15 69.85 0)
			(effects
				(font
					(size 1.27 1.27)
					(thickness 0.15)
				)
				(justify left bottom)
				(hide yes)
			)
		)
		(property "Footprint" "antmicro-footprints:C_0402_1005Metric"
			(at 313.69 69.85 0)
			(effects
				(font
					(size 1.27 1.27)
					(thickness 0.15)
				)
				(justify left bottom)
				(hide yes)
			)
		)
		(property "Datasheet" "https://www.murata.com/products/productdetail?partno=GRM155R61H104KE14%23"
			(at 316.23 69.85 0)
			(effects
				(font
					(size 1.27 1.27)
					(thickness 0.15)
				)
				(justify left bottom)
				(hide yes)
			)
		)
		(property "Description" ""
			(at 300.99 90.17 0)
			(effects
				(font
					(size 1.27 1.27)
				)
				(hide yes)
			)
		)
		(property "MPN" "GRM155R61H104KE14D"
			(at 318.77 69.85 0)
			(effects
				(font
					(size 1.27 1.27)
					(thickness 0.15)
				)
				(justify left bottom)
				(hide yes)
			)
		)
		(property "Manufacturer" "Murata"
			(at 321.31 69.85 0)
			(effects
				(font
					(size 1.27 1.27)
					(thickness 0.15)
				)
				(justify left bottom)
				(hide yes)
			)
		)
		(property "License" "Apache-2.0"
			(at 323.85 69.85 0)
			(effects
				(font
					(size 1.27 1.27)
					(thickness 0.15)
				)
				(justify left bottom)
				(hide yes)
			)
		)
		(property "Author" "Antmicro"
			(at 326.39 69.85 0)
			(effects
				(font
					(size 1.27 1.27)
					(thickness 0.15)
				)
				(justify left bottom)
				(hide yes)
			)
		)
		(property "Val" "100n"
			(at 303.3141 89.3167 90)
			(effects
				(font
					(size 1.27 1.27)
					(thickness 0.15)
				)
				(justify right)
			)
		)
		(property "Voltage" "50V"
			(at 328.93 69.85 0)
			(effects
				(font
					(size 1.27 1.27)
				)
				(justify left bottom)
				(hide yes)
			)
		)
		(property "Dielectric" "X5R"
			(at 331.47 69.85 0)
			(effects
				(font
					(size 1.27 1.27)
				)
				(justify left bottom)
				(hide yes)
			)
		)
		(pin "1"
		)
		(pin "2"
		)
		(instances
			(project "data-center-rdimm-ddr5-tester"
				(path ""
					(reference "C137")
					(unit 1)
				)
			)
		)
	)
	(symbol
		(lib_id "antmicroResistors0402:R_10k_0402")
		(at 317.5 161.29 0)
		(mirror y)
		(unit 1)
		(exclude_from_sim no)
		(in_bom yes)
		(on_board yes)
		(dnp no)
		(property "Reference" "R104"
			(at 321.31 160.02 0)
			(effects
				(font
					(size 1.27 1.27)
				)
			)
		)
		(property "Value" "R_10k_0402"
			(at 297.18 173.99 0)
			(effects
				(font
					(size 1.27 1.27)
					(thickness 0.15)
				)
				(justify left bottom)
				(hide yes)
			)
		)
		(property "Footprint" "antmicro-footprints:R_0402_1005Metric"
			(at 297.18 176.53 0)
			(effects
				(font
					(size 1.27 1.27)
					(thickness 0.15)
				)
				(justify left bottom)
				(hide yes)
			)
		)
		(property "Datasheet" "https://www.bourns.com/docs/product-datasheets/cr.pdf"
			(at 297.18 179.07 0)
			(effects
				(font
					(size 1.27 1.27)
					(thickness 0.15)
				)
				(justify left bottom)
				(hide yes)
			)
		)
		(property "Description" ""
			(at 317.5 161.29 0)
			(effects
				(font
					(size 1.27 1.27)
				)
				(hide yes)
			)
		)
		(property "Manufacturer" "Bourns"
			(at 297.18 184.15 0)
			(effects
				(font
					(size 1.27 1.27)
					(thickness 0.15)
				)
				(justify left bottom)
				(hide yes)
			)
		)
		(property "MPN" "CR0402-FX-1002GLF"
			(at 297.18 181.61 0)
			(effects
				(font
					(size 1.27 1.27)
					(thickness 0.15)
				)
				(justify left bottom)
				(hide yes)
			)
		)
		(property "Val" "10k"
			(at 310.515 160.02 0)
			(effects
				(font
					(size 1.27 1.27)
					(thickness 0.15)
				)
			)
		)
		(property "License" "Apache-2.0"
			(at 297.18 186.69 0)
			(effects
				(font
					(size 1.27 1.27)
					(thickness 0.15)
				)
				(justify left bottom)
				(hide yes)
			)
		)
		(property "Author" "Antmicro"
			(at 297.18 189.23 0)
			(effects
				(font
					(size 1.27 1.27)
					(thickness 0.15)
				)
				(justify left bottom)
				(hide yes)
			)
		)
		(property "Tolerance" "1%"
			(at 297.18 171.45 0)
			(effects
				(font
					(size 1.27 1.27)
				)
				(justify left bottom)
				(hide yes)
			)
		)
		(pin "1"
		)
		(pin "2"
		)
		(instances
			(project "data-center-rdimm-ddr5-tester"
				(path ""
					(reference "R104")
					(unit 1)
				)
			)
		)
	)
	(symbol
		(lib_id "antmicropower:GND")
		(at 311.15 95.25 0)
		(unit 1)
		(exclude_from_sim no)
		(in_bom yes)
		(on_board yes)
		(dnp no)
		(fields_autoplaced yes)
		(property "Reference" "#PWR0208"
			(at 311.15 101.6 0)
			(effects
				(font
					(size 1.27 1.27)
				)
				(hide yes)
			)
		)
		(property "Value" "GND"
			(at 309.245 99.695 0)
			(effects
				(font
					(size 1.27 1.27)
					(thickness 0.15)
				)
				(justify left bottom)
			)
		)
		(property "Footprint" ""
			(at 320.04 102.87 0)
			(effects
				(font
					(size 1.27 1.27)
					(thickness 0.15)
				)
				(justify left bottom)
				(hide yes)
			)
		)
		(property "Datasheet" ""
			(at 320.04 107.95 0)
			(effects
				(font
					(size 1.27 1.27)
					(thickness 0.15)
				)
				(justify left bottom)
				(hide yes)
			)
		)
		(property "Description" ""
			(at 311.15 95.25 0)
			(effects
				(font
					(size 1.27 1.27)
				)
				(hide yes)
			)
		)
		(property "Author" "Antmicro"
			(at 320.04 100.33 0)
			(effects
				(font
					(size 1.27 1.27)
					(thickness 0.15)
				)
				(justify left bottom)
				(hide yes)
			)
		)
		(property "License" "Apache-2.0"
			(at 320.04 102.87 0)
			(effects
				(font
					(size 1.27 1.27)
					(thickness 0.15)
				)
				(justify left bottom)
				(hide yes)
			)
		)
		(pin "1"
		)
		(instances
			(project "data-center-rdimm-ddr5-tester"
				(path ""
					(reference "#PWR0208")
					(unit 1)
				)
			)
		)
	)
	(symbol
		(lib_id "antmicroModularConnectorsJacks:RJ45_Abracon_ARJM11B1-502-AB-EW2")
		(at 322.58 53.34 0)
		(unit 1)
		(exclude_from_sim no)
		(in_bom yes)
		(on_board yes)
		(dnp no)
		(fields_autoplaced yes)
		(property "Reference" "J6"
			(at 334.01 45.72 0)
			(effects
				(font
					(size 1.27 1.27)
					(thickness 0.15)
				)
			)
		)
		(property "Value" "RJ45_Abracon_ARJM11B1-502-AB-EW2"
			(at 358.14 60.96 0)
			(effects
				(font
					(size 1.27 1.27)
					(thickness 0.15)
				)
				(justify left bottom)
				(hide yes)
			)
		)
		(property "Footprint" "antmicro-footprints:RJ45_ARJM11B1-502-AB-EW2_Horizontal"
			(at 358.14 63.5 0)
			(effects
				(font
					(size 1.27 1.27)
					(thickness 0.15)
				)
				(justify left bottom)
				(hide yes)
			)
		)
		(property "Datasheet" "https://www.mouser.com/datasheet/3/184/1/ARJM11.pdf"
			(at 358.14 66.04 0)
			(effects
				(font
					(size 1.27 1.27)
					(thickness 0.15)
				)
				(justify left bottom)
				(hide yes)
			)
		)
		(property "Description" "Modular Connectors / Ethernet Connectors RJ45 JACK W/MAG 1X1 1000BASE-T"
			(at 358.14 75.946 0)
			(effects
				(font
					(size 1.27 1.27)
				)
				(justify left bottom)
				(hide yes)
			)
		)
		(property "MPN" "ARJM11B1-502-AB-EW2"
			(at 334.01 48.26 0)
			(effects
				(font
					(size 1.27 1.27)
					(thickness 0.15)
				)
			)
		)
		(property "Manufacturer" "Abracon"
			(at 358.14 68.58 0)
			(effects
				(font
					(size 1.27 1.27)
					(thickness 0.15)
				)
				(justify left bottom)
				(hide yes)
			)
		)
		(property "Author" "Antmicro"
			(at 358.14 70.866 0)
			(effects
				(font
					(size 1.27 1.27)
					(thickness 0.15)
				)
				(justify left bottom)
				(hide yes)
			)
		)
		(property "License" "Apache-2.0"
			(at 358.14 73.406 0)
			(effects
				(font
					(size 1.27 1.27)
					(thickness 0.15)
				)
				(justify left bottom)
				(hide yes)
			)
		)
		(pin "12"
		)
		(pin "6"
		)
		(pin "11"
		)
		(pin "5"
		)
		(pin "14"
		)
		(pin "13"
		)
		(pin "9"
		)
		(pin "7"
		)
		(pin "8"
		)
		(pin "3"
		)
		(pin "4"
		)
		(pin "10"
		)
		(pin "2"
		)
		(pin "1"
		)
		(pin "SH"
		)
		(instances
			(project "data-center-rdimm-ddr5-tester"
				(path ""
					(reference "J6")
					(unit 1)
				)
			)
		)
	)
	(symbol
		(lib_id "antmicropower:GND")
		(at 208.28 114.3 0)
		(mirror y)
		(unit 1)
		(exclude_from_sim no)
		(in_bom yes)
		(on_board yes)
		(dnp no)
		(fields_autoplaced yes)
		(property "Reference" "#PWR0417"
			(at 208.28 120.65 0)
			(effects
				(font
					(size 1.27 1.27)
				)
				(hide yes)
			)
		)
		(property "Value" "GND"
			(at 210.185 118.745 0)
			(effects
				(font
					(size 1.27 1.27)
					(thickness 0.15)
				)
				(justify left bottom)
			)
		)
		(property "Footprint" ""
			(at 199.39 121.92 0)
			(effects
				(font
					(size 1.27 1.27)
					(thickness 0.15)
				)
				(justify left bottom)
				(hide yes)
			)
		)
		(property "Datasheet" ""
			(at 199.39 127 0)
			(effects
				(font
					(size 1.27 1.27)
					(thickness 0.15)
				)
				(justify left bottom)
				(hide yes)
			)
		)
		(property "Description" ""
			(at 208.28 114.3 0)
			(effects
				(font
					(size 1.27 1.27)
				)
				(hide yes)
			)
		)
		(property "Author" "Antmicro"
			(at 199.39 119.38 0)
			(effects
				(font
					(size 1.27 1.27)
					(thickness 0.15)
				)
				(justify left bottom)
				(hide yes)
			)
		)
		(property "License" "Apache-2.0"
			(at 199.39 121.92 0)
			(effects
				(font
					(size 1.27 1.27)
					(thickness 0.15)
				)
				(justify left bottom)
				(hide yes)
			)
		)
		(pin "1"
		)
		(instances
			(project "data-center-rdimm-ddr5-tester"
				(path ""
					(reference "#PWR0417")
					(unit 1)
				)
			)
		)
	)
	(symbol
		(lib_id "antmicropower:+1V8")
		(at 62.23 138.43 0)
		(unit 1)
		(exclude_from_sim no)
		(in_bom yes)
		(on_board yes)
		(dnp no)
		(fields_autoplaced yes)
		(property "Reference" "#PWR0238"
			(at 77.47 140.97 0)
			(effects
				(font
					(size 1.27 1.27)
					(thickness 0.15)
				)
				(justify left bottom)
				(hide yes)
			)
		)
		(property "Value" "+1V8"
			(at 62.23 133.985 0)
			(effects
				(font
					(size 1.27 1.27)
					(thickness 0.15)
				)
			)
		)
		(property "Footprint" ""
			(at 77.47 146.05 0)
			(effects
				(font
					(size 1.27 1.27)
					(thickness 0.15)
				)
				(justify left bottom)
				(hide yes)
			)
		)
		(property "Datasheet" ""
			(at 77.47 148.59 0)
			(effects
				(font
					(size 1.27 1.27)
					(thickness 0.15)
				)
				(justify left bottom)
				(hide yes)
			)
		)
		(property "Description" ""
			(at 62.23 138.43 0)
			(effects
				(font
					(size 1.27 1.27)
				)
				(hide yes)
			)
		)
		(property "Author" "Antmicro"
			(at 77.47 143.51 0)
			(effects
				(font
					(size 1.27 1.27)
					(thickness 0.15)
				)
				(justify left bottom)
				(hide yes)
			)
		)
		(property "License" "Apache-2.0"
			(at 77.47 146.05 0)
			(effects
				(font
					(size 1.27 1.27)
					(thickness 0.15)
				)
				(justify left bottom)
				(hide yes)
			)
		)
		(pin "1"
		)
		(instances
			(project "data-center-rdimm-ddr5-tester"
				(path ""
					(reference "#PWR0238")
					(unit 1)
				)
			)
		)
	)
	(symbol
		(lib_id "antmicroResistors0402:R_10k_0402")
		(at 317.5 180.34 0)
		(mirror y)
		(unit 1)
		(exclude_from_sim no)
		(in_bom no)
		(on_board yes)
		(dnp yes)
		(property "Reference" "R105"
			(at 321.31 179.07 0)
			(effects
				(font
					(size 1.27 1.27)
				)
			)
		)
		(property "Value" "R_10k_0402"
			(at 297.18 193.04 0)
			(effects
				(font
					(size 1.27 1.27)
					(thickness 0.15)
				)
				(justify left bottom)
				(hide yes)
			)
		)
		(property "Footprint" "antmicro-footprints:R_0402_1005Metric"
			(at 297.18 195.58 0)
			(effects
				(font
					(size 1.27 1.27)
					(thickness 0.15)
				)
				(justify left bottom)
				(hide yes)
			)
		)
		(property "Datasheet" "https://www.bourns.com/docs/product-datasheets/cr.pdf"
			(at 297.18 198.12 0)
			(effects
				(font
					(size 1.27 1.27)
					(thickness 0.15)
				)
				(justify left bottom)
				(hide yes)
			)
		)
		(property "Description" ""
			(at 317.5 180.34 0)
			(effects
				(font
					(size 1.27 1.27)
				)
				(hide yes)
			)
		)
		(property "Manufacturer" "Bourns"
			(at 297.18 203.2 0)
			(effects
				(font
					(size 1.27 1.27)
					(thickness 0.15)
				)
				(justify left bottom)
				(hide yes)
			)
		)
		(property "MPN" "CR0402-FX-1002GLF"
			(at 297.18 200.66 0)
			(effects
				(font
					(size 1.27 1.27)
					(thickness 0.15)
				)
				(justify left bottom)
				(hide yes)
			)
		)
		(property "Val" "10k"
			(at 310.515 179.07 0)
			(effects
				(font
					(size 1.27 1.27)
					(thickness 0.15)
				)
			)
		)
		(property "License" "Apache-2.0"
			(at 297.18 205.74 0)
			(effects
				(font
					(size 1.27 1.27)
					(thickness 0.15)
				)
				(justify left bottom)
				(hide yes)
			)
		)
		(property "Author" "Antmicro"
			(at 297.18 208.28 0)
			(effects
				(font
					(size 1.27 1.27)
					(thickness 0.15)
				)
				(justify left bottom)
				(hide yes)
			)
		)
		(property "Tolerance" "1%"
			(at 297.18 190.5 0)
			(effects
				(font
					(size 1.27 1.27)
				)
				(justify left bottom)
				(hide yes)
			)
		)
		(pin "1"
		)
		(pin "2"
		)
		(instances
			(project "data-center-rdimm-ddr5-tester"
				(path ""
					(reference "R105")
					(unit 1)
				)
			)
		)
	)
	(symbol
		(lib_id "antmicropower:GND")
		(at 68.58 113.03 0)
		(unit 1)
		(exclude_from_sim no)
		(in_bom yes)
		(on_board yes)
		(dnp no)
		(property "Reference" "#PWR0354"
			(at 68.58 119.38 0)
			(effects
				(font
					(size 1.27 1.27)
				)
				(hide yes)
			)
		)
		(property "Value" "GND"
			(at 66.675 117.475 0)
			(effects
				(font
					(size 1.27 1.27)
					(thickness 0.15)
				)
				(justify left bottom)
			)
		)
		(property "Footprint" ""
			(at 77.47 120.65 0)
			(effects
				(font
					(size 1.27 1.27)
					(thickness 0.15)
				)
				(justify left bottom)
				(hide yes)
			)
		)
		(property "Datasheet" ""
			(at 77.47 125.73 0)
			(effects
				(font
					(size 1.27 1.27)
					(thickness 0.15)
				)
				(justify left bottom)
				(hide yes)
			)
		)
		(property "Description" ""
			(at 68.58 113.03 0)
			(effects
				(font
					(size 1.27 1.27)
				)
				(hide yes)
			)
		)
		(property "Author" "Antmicro"
			(at 77.47 118.11 0)
			(effects
				(font
					(size 1.27 1.27)
					(thickness 0.15)
				)
				(justify left bottom)
				(hide yes)
			)
		)
		(property "License" "Apache-2.0"
			(at 77.47 120.65 0)
			(effects
				(font
					(size 1.27 1.27)
					(thickness 0.15)
				)
				(justify left bottom)
				(hide yes)
			)
		)
		(pin "1"
		)
		(instances
			(project "data-center-rdimm-ddr5-tester"
				(path ""
					(reference "#PWR0354")
					(unit 1)
				)
			)
		)
	)
	(symbol
		(lib_id "antmicropower:GND")
		(at 199.39 114.3 0)
		(mirror y)
		(unit 1)
		(exclude_from_sim no)
		(in_bom yes)
		(on_board yes)
		(dnp no)
		(fields_autoplaced yes)
		(property "Reference" "#PWR0418"
			(at 199.39 120.65 0)
			(effects
				(font
					(size 1.27 1.27)
				)
				(hide yes)
			)
		)
		(property "Value" "GND"
			(at 201.295 118.745 0)
			(effects
				(font
					(size 1.27 1.27)
					(thickness 0.15)
				)
				(justify left bottom)
			)
		)
		(property "Footprint" ""
			(at 190.5 121.92 0)
			(effects
				(font
					(size 1.27 1.27)
					(thickness 0.15)
				)
				(justify left bottom)
				(hide yes)
			)
		)
		(property "Datasheet" ""
			(at 190.5 127 0)
			(effects
				(font
					(size 1.27 1.27)
					(thickness 0.15)
				)
				(justify left bottom)
				(hide yes)
			)
		)
		(property "Description" ""
			(at 199.39 114.3 0)
			(effects
				(font
					(size 1.27 1.27)
				)
				(hide yes)
			)
		)
		(property "Author" "Antmicro"
			(at 190.5 119.38 0)
			(effects
				(font
					(size 1.27 1.27)
					(thickness 0.15)
				)
				(justify left bottom)
				(hide yes)
			)
		)
		(property "License" "Apache-2.0"
			(at 190.5 121.92 0)
			(effects
				(font
					(size 1.27 1.27)
					(thickness 0.15)
				)
				(justify left bottom)
				(hide yes)
			)
		)
		(pin "1"
		)
		(instances
			(project "data-center-rdimm-ddr5-tester"
				(path ""
					(reference "#PWR0418")
					(unit 1)
				)
			)
		)
	)
	(symbol
		(lib_id "antmicropower:GND")
		(at 54.61 134.62 0)
		(unit 1)
		(exclude_from_sim no)
		(in_bom yes)
		(on_board yes)
		(dnp no)
		(fields_autoplaced yes)
		(property "Reference" "#PWR0405"
			(at 54.61 140.97 0)
			(effects
				(font
					(size 1.27 1.27)
				)
				(hide yes)
			)
		)
		(property "Value" "GND"
			(at 52.705 139.065 0)
			(effects
				(font
					(size 1.27 1.27)
					(thickness 0.15)
				)
				(justify left bottom)
			)
		)
		(property "Footprint" ""
			(at 63.5 142.24 0)
			(effects
				(font
					(size 1.27 1.27)
					(thickness 0.15)
				)
				(justify left bottom)
				(hide yes)
			)
		)
		(property "Datasheet" ""
			(at 63.5 147.32 0)
			(effects
				(font
					(size 1.27 1.27)
					(thickness 0.15)
				)
				(justify left bottom)
				(hide yes)
			)
		)
		(property "Description" ""
			(at 54.61 134.62 0)
			(effects
				(font
					(size 1.27 1.27)
				)
				(hide yes)
			)
		)
		(property "Author" "Antmicro"
			(at 63.5 139.7 0)
			(effects
				(font
					(size 1.27 1.27)
					(thickness 0.15)
				)
				(justify left bottom)
				(hide yes)
			)
		)
		(property "License" "Apache-2.0"
			(at 63.5 142.24 0)
			(effects
				(font
					(size 1.27 1.27)
					(thickness 0.15)
				)
				(justify left bottom)
				(hide yes)
			)
		)
		(pin "1"
		)
		(instances
			(project "data-center-rdimm-ddr5-tester"
				(path ""
					(reference "#PWR0405")
					(unit 1)
				)
			)
		)
	)
	(symbol
		(lib_id "antmicropower:GND")
		(at 175.26 151.13 0)
		(unit 1)
		(exclude_from_sim no)
		(in_bom yes)
		(on_board yes)
		(dnp no)
		(fields_autoplaced yes)
		(property "Reference" "#PWR0414"
			(at 175.26 157.48 0)
			(effects
				(font
					(size 1.27 1.27)
				)
				(hide yes)
			)
		)
		(property "Value" "GND"
			(at 173.355 155.575 0)
			(effects
				(font
					(size 1.27 1.27)
					(thickness 0.15)
				)
				(justify left bottom)
			)
		)
		(property "Footprint" ""
			(at 184.15 158.75 0)
			(effects
				(font
					(size 1.27 1.27)
					(thickness 0.15)
				)
				(justify left bottom)
				(hide yes)
			)
		)
		(property "Datasheet" ""
			(at 184.15 163.83 0)
			(effects
				(font
					(size 1.27 1.27)
					(thickness 0.15)
				)
				(justify left bottom)
				(hide yes)
			)
		)
		(property "Description" ""
			(at 175.26 151.13 0)
			(effects
				(font
					(size 1.27 1.27)
				)
				(hide yes)
			)
		)
		(property "Author" "Antmicro"
			(at 184.15 156.21 0)
			(effects
				(font
					(size 1.27 1.27)
					(thickness 0.15)
				)
				(justify left bottom)
				(hide yes)
			)
		)
		(property "License" "Apache-2.0"
			(at 184.15 158.75 0)
			(effects
				(font
					(size 1.27 1.27)
					(thickness 0.15)
				)
				(justify left bottom)
				(hide yes)
			)
		)
		(pin "1"
		)
		(instances
			(project "data-center-rdimm-ddr5-tester"
				(path ""
					(reference "#PWR0414")
					(unit 1)
				)
			)
		)
	)
	(symbol
		(lib_id "antmicropower:GND")
		(at 182.88 151.13 0)
		(unit 1)
		(exclude_from_sim no)
		(in_bom yes)
		(on_board yes)
		(dnp no)
		(fields_autoplaced yes)
		(property "Reference" "#PWR0413"
			(at 182.88 157.48 0)
			(effects
				(font
					(size 1.27 1.27)
				)
				(hide yes)
			)
		)
		(property "Value" "GND"
			(at 180.975 155.575 0)
			(effects
				(font
					(size 1.27 1.27)
					(thickness 0.15)
				)
				(justify left bottom)
			)
		)
		(property "Footprint" ""
			(at 191.77 158.75 0)
			(effects
				(font
					(size 1.27 1.27)
					(thickness 0.15)
				)
				(justify left bottom)
				(hide yes)
			)
		)
		(property "Datasheet" ""
			(at 191.77 163.83 0)
			(effects
				(font
					(size 1.27 1.27)
					(thickness 0.15)
				)
				(justify left bottom)
				(hide yes)
			)
		)
		(property "Description" ""
			(at 182.88 151.13 0)
			(effects
				(font
					(size 1.27 1.27)
				)
				(hide yes)
			)
		)
		(property "Author" "Antmicro"
			(at 191.77 156.21 0)
			(effects
				(font
					(size 1.27 1.27)
					(thickness 0.15)
				)
				(justify left bottom)
				(hide yes)
			)
		)
		(property "License" "Apache-2.0"
			(at 191.77 158.75 0)
			(effects
				(font
					(size 1.27 1.27)
					(thickness 0.15)
				)
				(justify left bottom)
				(hide yes)
			)
		)
		(pin "1"
		)
		(instances
			(project "data-center-rdimm-ddr5-tester"
				(path ""
					(reference "#PWR0413")
					(unit 1)
				)
			)
		)
	)
	(symbol
		(lib_id "antmicropower:GND")
		(at 175.26 114.3 0)
		(mirror y)
		(unit 1)
		(exclude_from_sim no)
		(in_bom yes)
		(on_board yes)
		(dnp no)
		(fields_autoplaced yes)
		(property "Reference" "#PWR0411"
			(at 175.26 120.65 0)
			(effects
				(font
					(size 1.27 1.27)
				)
				(hide yes)
			)
		)
		(property "Value" "GND"
			(at 177.165 118.745 0)
			(effects
				(font
					(size 1.27 1.27)
					(thickness 0.15)
				)
				(justify left bottom)
			)
		)
		(property "Footprint" ""
			(at 166.37 121.92 0)
			(effects
				(font
					(size 1.27 1.27)
					(thickness 0.15)
				)
				(justify left bottom)
				(hide yes)
			)
		)
		(property "Datasheet" ""
			(at 166.37 127 0)
			(effects
				(font
					(size 1.27 1.27)
					(thickness 0.15)
				)
				(justify left bottom)
				(hide yes)
			)
		)
		(property "Description" ""
			(at 175.26 114.3 0)
			(effects
				(font
					(size 1.27 1.27)
				)
				(hide yes)
			)
		)
		(property "Author" "Antmicro"
			(at 166.37 119.38 0)
			(effects
				(font
					(size 1.27 1.27)
					(thickness 0.15)
				)
				(justify left bottom)
				(hide yes)
			)
		)
		(property "License" "Apache-2.0"
			(at 166.37 121.92 0)
			(effects
				(font
					(size 1.27 1.27)
					(thickness 0.15)
				)
				(justify left bottom)
				(hide yes)
			)
		)
		(pin "1"
		)
		(instances
			(project "data-center-rdimm-ddr5-tester"
				(path ""
					(reference "#PWR0411")
					(unit 1)
				)
			)
		)
	)
	(symbol
		(lib_id "antmicropower:GND")
		(at 191.77 134.62 0)
		(unit 1)
		(exclude_from_sim no)
		(in_bom yes)
		(on_board yes)
		(dnp no)
		(fields_autoplaced yes)
		(property "Reference" "#PWR0416"
			(at 191.77 140.97 0)
			(effects
				(font
					(size 1.27 1.27)
				)
				(hide yes)
			)
		)
		(property "Value" "GND"
			(at 189.865 139.065 0)
			(effects
				(font
					(size 1.27 1.27)
					(thickness 0.15)
				)
				(justify left bottom)
			)
		)
		(property "Footprint" ""
			(at 200.66 142.24 0)
			(effects
				(font
					(size 1.27 1.27)
					(thickness 0.15)
				)
				(justify left bottom)
				(hide yes)
			)
		)
		(property "Datasheet" ""
			(at 200.66 147.32 0)
			(effects
				(font
					(size 1.27 1.27)
					(thickness 0.15)
				)
				(justify left bottom)
				(hide yes)
			)
		)
		(property "Description" ""
			(at 191.77 134.62 0)
			(effects
				(font
					(size 1.27 1.27)
				)
				(hide yes)
			)
		)
		(property "Author" "Antmicro"
			(at 200.66 139.7 0)
			(effects
				(font
					(size 1.27 1.27)
					(thickness 0.15)
				)
				(justify left bottom)
				(hide yes)
			)
		)
		(property "License" "Apache-2.0"
			(at 200.66 142.24 0)
			(effects
				(font
					(size 1.27 1.27)
					(thickness 0.15)
				)
				(justify left bottom)
				(hide yes)
			)
		)
		(pin "1"
		)
		(instances
			(project "data-center-rdimm-ddr5-tester"
				(path ""
					(reference "#PWR0416")
					(unit 1)
				)
			)
		)
	)
	(symbol
		(lib_id "antmicropower:+1V8")
		(at 337.82 231.14 0)
		(unit 1)
		(exclude_from_sim no)
		(in_bom yes)
		(on_board yes)
		(dnp no)
		(fields_autoplaced yes)
		(property "Reference" "#PWR0254"
			(at 353.06 233.68 0)
			(effects
				(font
					(size 1.27 1.27)
					(thickness 0.15)
				)
				(justify left bottom)
				(hide yes)
			)
		)
		(property "Value" "+1V8"
			(at 337.82 226.695 0)
			(effects
				(font
					(size 1.27 1.27)
					(thickness 0.15)
				)
			)
		)
		(property "Footprint" ""
			(at 353.06 238.76 0)
			(effects
				(font
					(size 1.27 1.27)
					(thickness 0.15)
				)
				(justify left bottom)
				(hide yes)
			)
		)
		(property "Datasheet" ""
			(at 353.06 241.3 0)
			(effects
				(font
					(size 1.27 1.27)
					(thickness 0.15)
				)
				(justify left bottom)
				(hide yes)
			)
		)
		(property "Description" ""
			(at 337.82 231.14 0)
			(effects
				(font
					(size 1.27 1.27)
				)
				(hide yes)
			)
		)
		(property "Author" "Antmicro"
			(at 353.06 236.22 0)
			(effects
				(font
					(size 1.27 1.27)
					(thickness 0.15)
				)
				(justify left bottom)
				(hide yes)
			)
		)
		(property "License" "Apache-2.0"
			(at 353.06 238.76 0)
			(effects
				(font
					(size 1.27 1.27)
					(thickness 0.15)
				)
				(justify left bottom)
				(hide yes)
			)
		)
		(pin "1"
		)
		(instances
			(project "data-center-rdimm-ddr5-tester"
				(path ""
					(reference "#PWR0254")
					(unit 1)
				)
			)
		)
	)
	(symbol
		(lib_id "antmicropower:+1V8")
		(at 326.39 231.14 0)
		(unit 1)
		(exclude_from_sim no)
		(in_bom yes)
		(on_board yes)
		(dnp no)
		(fields_autoplaced yes)
		(property "Reference" "#PWR0252"
			(at 341.63 233.68 0)
			(effects
				(font
					(size 1.27 1.27)
					(thickness 0.15)
				)
				(justify left bottom)
				(hide yes)
			)
		)
		(property "Value" "+1V8"
			(at 326.39 226.695 0)
			(effects
				(font
					(size 1.27 1.27)
					(thickness 0.15)
				)
			)
		)
		(property "Footprint" ""
			(at 341.63 238.76 0)
			(effects
				(font
					(size 1.27 1.27)
					(thickness 0.15)
				)
				(justify left bottom)
				(hide yes)
			)
		)
		(property "Datasheet" ""
			(at 341.63 241.3 0)
			(effects
				(font
					(size 1.27 1.27)
					(thickness 0.15)
				)
				(justify left bottom)
				(hide yes)
			)
		)
		(property "Description" ""
			(at 326.39 231.14 0)
			(effects
				(font
					(size 1.27 1.27)
				)
				(hide yes)
			)
		)
		(property "Author" "Antmicro"
			(at 341.63 236.22 0)
			(effects
				(font
					(size 1.27 1.27)
					(thickness 0.15)
				)
				(justify left bottom)
				(hide yes)
			)
		)
		(property "License" "Apache-2.0"
			(at 341.63 238.76 0)
			(effects
				(font
					(size 1.27 1.27)
					(thickness 0.15)
				)
				(justify left bottom)
				(hide yes)
			)
		)
		(pin "1"
		)
		(instances
			(project "data-center-rdimm-ddr5-tester"
				(path ""
					(reference "#PWR0252")
					(unit 1)
				)
			)
		)
	)
	(symbol
		(lib_id "antmicropower:GND")
		(at 182.88 114.3 0)
		(mirror y)
		(unit 1)
		(exclude_from_sim no)
		(in_bom yes)
		(on_board yes)
		(dnp no)
		(fields_autoplaced yes)
		(property "Reference" "#PWR0410"
			(at 182.88 120.65 0)
			(effects
				(font
					(size 1.27 1.27)
				)
				(hide yes)
			)
		)
		(property "Value" "GND"
			(at 184.785 118.745 0)
			(effects
				(font
					(size 1.27 1.27)
					(thickness 0.15)
				)
				(justify left bottom)
			)
		)
		(property "Footprint" ""
			(at 173.99 121.92 0)
			(effects
				(font
					(size 1.27 1.27)
					(thickness 0.15)
				)
				(justify left bottom)
				(hide yes)
			)
		)
		(property "Datasheet" ""
			(at 173.99 127 0)
			(effects
				(font
					(size 1.27 1.27)
					(thickness 0.15)
				)
				(justify left bottom)
				(hide yes)
			)
		)
		(property "Description" ""
			(at 182.88 114.3 0)
			(effects
				(font
					(size 1.27 1.27)
				)
				(hide yes)
			)
		)
		(property "Author" "Antmicro"
			(at 173.99 119.38 0)
			(effects
				(font
					(size 1.27 1.27)
					(thickness 0.15)
				)
				(justify left bottom)
				(hide yes)
			)
		)
		(property "License" "Apache-2.0"
			(at 173.99 121.92 0)
			(effects
				(font
					(size 1.27 1.27)
					(thickness 0.15)
				)
				(justify left bottom)
				(hide yes)
			)
		)
		(pin "1"
		)
		(instances
			(project "data-center-rdimm-ddr5-tester"
				(path ""
					(reference "#PWR0410")
					(unit 1)
				)
			)
		)
	)
	(symbol
		(lib_id "antmicroCapacitors0402:C_100n_0402")
		(at 182.88 149.86 90)
		(unit 1)
		(exclude_from_sim no)
		(in_bom yes)
		(on_board yes)
		(dnp no)
		(property "Reference" "C157"
			(at 183.515 145.4313 90)
			(effects
				(font
					(size 1.27 1.27)
					(thickness 0.15)
				)
				(justify right)
			)
		)
		(property "Value" "C_100n_0402"
			(at 193.04 129.54 0)
			(effects
				(font
					(size 1.27 1.27)
					(thickness 0.15)
				)
				(justify left bottom)
				(hide yes)
			)
		)
		(property "Footprint" "antmicro-footprints:C_0402_1005Metric"
			(at 195.58 129.54 0)
			(effects
				(font
					(size 1.27 1.27)
					(thickness 0.15)
				)
				(justify left bottom)
				(hide yes)
			)
		)
		(property "Datasheet" "https://www.murata.com/products/productdetail?partno=GRM155R61H104KE14%23"
			(at 198.12 129.54 0)
			(effects
				(font
					(size 1.27 1.27)
					(thickness 0.15)
				)
				(justify left bottom)
				(hide yes)
			)
		)
		(property "Description" ""
			(at 182.88 149.86 0)
			(effects
				(font
					(size 1.27 1.27)
				)
				(hide yes)
			)
		)
		(property "MPN" "GRM155R61H104KE14D"
			(at 200.66 129.54 0)
			(effects
				(font
					(size 1.27 1.27)
					(thickness 0.15)
				)
				(justify left bottom)
				(hide yes)
			)
		)
		(property "Manufacturer" "Murata"
			(at 203.2 129.54 0)
			(effects
				(font
					(size 1.27 1.27)
					(thickness 0.15)
				)
				(justify left bottom)
				(hide yes)
			)
		)
		(property "License" "Apache-2.0"
			(at 205.74 129.54 0)
			(effects
				(font
					(size 1.27 1.27)
					(thickness 0.15)
				)
				(justify left bottom)
				(hide yes)
			)
		)
		(property "Author" "Antmicro"
			(at 208.28 129.54 0)
			(effects
				(font
					(size 1.27 1.27)
					(thickness 0.15)
				)
				(justify left bottom)
				(hide yes)
			)
		)
		(property "Val" "100n"
			(at 183.515 149.225 90)
			(effects
				(font
					(size 1.27 1.27)
					(thickness 0.15)
				)
				(justify right)
			)
		)
		(property "Voltage" "50V"
			(at 210.82 129.54 0)
			(effects
				(font
					(size 1.27 1.27)
				)
				(justify left bottom)
				(hide yes)
			)
		)
		(property "Dielectric" "X5R"
			(at 213.36 129.54 0)
			(effects
				(font
					(size 1.27 1.27)
				)
				(justify left bottom)
				(hide yes)
			)
		)
		(pin "1"
		)
		(pin "2"
		)
		(instances
			(project "data-center-rdimm-ddr5-tester"
				(path ""
					(reference "C157")
					(unit 1)
				)
			)
		)
	)
	(symbol
		(lib_id "antmicropower:GND")
		(at 46.99 134.62 0)
		(unit 1)
		(exclude_from_sim no)
		(in_bom yes)
		(on_board yes)
		(dnp no)
		(fields_autoplaced yes)
		(property "Reference" "#PWR0355"
			(at 46.99 140.97 0)
			(effects
				(font
					(size 1.27 1.27)
				)
				(hide yes)
			)
		)
		(property "Value" "GND"
			(at 45.085 139.065 0)
			(effects
				(font
					(size 1.27 1.27)
					(thickness 0.15)
				)
				(justify left bottom)
			)
		)
		(property "Footprint" ""
			(at 55.88 142.24 0)
			(effects
				(font
					(size 1.27 1.27)
					(thickness 0.15)
				)
				(justify left bottom)
				(hide yes)
			)
		)
		(property "Datasheet" ""
			(at 55.88 147.32 0)
			(effects
				(font
					(size 1.27 1.27)
					(thickness 0.15)
				)
				(justify left bottom)
				(hide yes)
			)
		)
		(property "Description" ""
			(at 46.99 134.62 0)
			(effects
				(font
					(size 1.27 1.27)
				)
				(hide yes)
			)
		)
		(property "Author" "Antmicro"
			(at 55.88 139.7 0)
			(effects
				(font
					(size 1.27 1.27)
					(thickness 0.15)
				)
				(justify left bottom)
				(hide yes)
			)
		)
		(property "License" "Apache-2.0"
			(at 55.88 142.24 0)
			(effects
				(font
					(size 1.27 1.27)
					(thickness 0.15)
				)
				(justify left bottom)
				(hide yes)
			)
		)
		(pin "1"
		)
		(instances
			(project "data-center-rdimm-ddr5-tester"
				(path ""
					(reference "#PWR0355")
					(unit 1)
				)
			)
		)
	)
	(symbol
		(lib_id "antmicropower:GND")
		(at 77.47 113.03 0)
		(unit 1)
		(exclude_from_sim no)
		(in_bom yes)
		(on_board yes)
		(dnp no)
		(property "Reference" "#PWR0353"
			(at 77.47 119.38 0)
			(effects
				(font
					(size 1.27 1.27)
				)
				(hide yes)
			)
		)
		(property "Value" "GND"
			(at 75.565 117.475 0)
			(effects
				(font
					(size 1.27 1.27)
					(thickness 0.15)
				)
				(justify left bottom)
			)
		)
		(property "Footprint" ""
			(at 86.36 120.65 0)
			(effects
				(font
					(size 1.27 1.27)
					(thickness 0.15)
				)
				(justify left bottom)
				(hide yes)
			)
		)
		(property "Datasheet" ""
			(at 86.36 125.73 0)
			(effects
				(font
					(size 1.27 1.27)
					(thickness 0.15)
				)
				(justify left bottom)
				(hide yes)
			)
		)
		(property "Description" ""
			(at 77.47 113.03 0)
			(effects
				(font
					(size 1.27 1.27)
				)
				(hide yes)
			)
		)
		(property "Author" "Antmicro"
			(at 86.36 118.11 0)
			(effects
				(font
					(size 1.27 1.27)
					(thickness 0.15)
				)
				(justify left bottom)
				(hide yes)
			)
		)
		(property "License" "Apache-2.0"
			(at 86.36 120.65 0)
			(effects
				(font
					(size 1.27 1.27)
					(thickness 0.15)
				)
				(justify left bottom)
				(hide yes)
			)
		)
		(pin "1"
		)
		(instances
			(project "data-center-rdimm-ddr5-tester"
				(path ""
					(reference "#PWR0353")
					(unit 1)
				)
			)
		)
	)
	(symbol
		(lib_id "antmicropower:PWR_FLAG")
		(at 228.6 127 0)
		(unit 1)
		(exclude_from_sim no)
		(in_bom yes)
		(on_board yes)
		(dnp no)
		(fields_autoplaced yes)
		(property "Reference" "#FLG0105"
			(at 228.6 125.095 0)
			(effects
				(font
					(size 1.27 1.27)
				)
				(hide yes)
			)
		)
		(property "Value" "PWR_FLAG"
			(at 228.6 123.4242 0)
			(effects
				(font
					(size 1.27 1.27)
				)
			)
		)
		(property "Footprint" ""
			(at 228.6 127 0)
			(effects
				(font
					(size 1.27 1.27)
				)
				(hide yes)
			)
		)
		(property "Datasheet" ""
			(at 228.6 127 0)
			(effects
				(font
					(size 1.27 1.27)
				)
				(hide yes)
			)
		)
		(property "Description" ""
			(at 228.6 127 0)
			(effects
				(font
					(size 1.27 1.27)
				)
				(hide yes)
			)
		)
		(pin "1"
		)
		(instances
			(project "data-center-rdimm-ddr5-tester"
				(path ""
					(reference "#FLG0105")
					(unit 1)
				)
			)
		)
	)
	(symbol
		(lib_id "antmicroFerriteBeadsandChips:FB_120Z_2A_Murata-BLM18PG_0603")
		(at 30.48 124.46 0)
		(unit 1)
		(exclude_from_sim no)
		(in_bom yes)
		(on_board yes)
		(dnp no)
		(fields_autoplaced yes)
		(property "Reference" "FB5"
			(at 32.9819 119.065 0)
			(effects
				(font
					(size 1.27 1.27)
					(thickness 0.15)
				)
			)
		)
		(property "Value" "FB_120Z_2A_Murata-BLM18PG_0603"
			(at 45.72 127 0)
			(effects
				(font
					(size 1.27 1.27)
					(thickness 0.15)
				)
				(justify left bottom)
				(hide yes)
			)
		)
		(property "Footprint" "antmicro-footprints:FB_0603_1608Metric"
			(at 45.72 132.08 0)
			(effects
				(font
					(size 1.27 1.27)
					(thickness 0.15)
				)
				(justify left bottom)
				(hide yes)
			)
		)
		(property "Datasheet" "https://www.murata.com/en-us/products/productdata/8796738650142/ENFA0003.pdf"
			(at 45.72 134.62 0)
			(effects
				(font
					(size 1.27 1.27)
					(thickness 0.15)
				)
				(justify left bottom)
				(hide yes)
			)
		)
		(property "Description" ""
			(at 30.48 124.46 0)
			(effects
				(font
					(size 1.27 1.27)
				)
				(hide yes)
			)
		)
		(property "Val" "120Z/2A"
			(at 32.9819 121.5953 0)
			(effects
				(font
					(size 1.27 1.27)
				)
			)
		)
		(property "MPN" "BLM18PG121SN1D"
			(at 45.72 137.16 0)
			(effects
				(font
					(size 1.27 1.27)
					(thickness 0.15)
				)
				(justify left bottom)
				(hide yes)
			)
		)
		(property "Manufacturer" "Murata"
			(at 45.72 139.7 0)
			(effects
				(font
					(size 1.27 1.27)
					(thickness 0.15)
				)
				(justify left bottom)
				(hide yes)
			)
		)
		(property "Author" "Antmicro"
			(at 45.72 142.24 0)
			(effects
				(font
					(size 1.27 1.27)
					(thickness 0.15)
				)
				(justify left bottom)
				(hide yes)
			)
		)
		(property "License" "Apache-2.0"
			(at 45.72 144.78 0)
			(effects
				(font
					(size 1.27 1.27)
					(thickness 0.15)
				)
				(justify left bottom)
				(hide yes)
			)
		)
		(pin "1"
		)
		(pin "2"
		)
		(instances
			(project "data-center-rdimm-ddr5-tester"
				(path ""
					(reference "FB5")
					(unit 1)
				)
			)
		)
	)
	(symbol
		(lib_id "antmicroResistors0402:R_10k_0402")
		(at 317.5 166.37 0)
		(mirror y)
		(unit 1)
		(exclude_from_sim no)
		(in_bom no)
		(on_board yes)
		(dnp yes)
		(property "Reference" "R102"
			(at 321.31 165.1 0)
			(effects
				(font
					(size 1.27 1.27)
				)
			)
		)
		(property "Value" "R_10k_0402"
			(at 297.18 179.07 0)
			(effects
				(font
					(size 1.27 1.27)
					(thickness 0.15)
				)
				(justify left bottom)
				(hide yes)
			)
		)
		(property "Footprint" "antmicro-footprints:R_0402_1005Metric"
			(at 297.18 181.61 0)
			(effects
				(font
					(size 1.27 1.27)
					(thickness 0.15)
				)
				(justify left bottom)
				(hide yes)
			)
		)
		(property "Datasheet" "https://www.bourns.com/docs/product-datasheets/cr.pdf"
			(at 297.18 184.15 0)
			(effects
				(font
					(size 1.27 1.27)
					(thickness 0.15)
				)
				(justify left bottom)
				(hide yes)
			)
		)
		(property "Description" ""
			(at 317.5 166.37 0)
			(effects
				(font
					(size 1.27 1.27)
				)
				(hide yes)
			)
		)
		(property "Manufacturer" "Bourns"
			(at 297.18 189.23 0)
			(effects
				(font
					(size 1.27 1.27)
					(thickness 0.15)
				)
				(justify left bottom)
				(hide yes)
			)
		)
		(property "MPN" "CR0402-FX-1002GLF"
			(at 297.18 186.69 0)
			(effects
				(font
					(size 1.27 1.27)
					(thickness 0.15)
				)
				(justify left bottom)
				(hide yes)
			)
		)
		(property "Val" "10k"
			(at 310.515 165.1 0)
			(effects
				(font
					(size 1.27 1.27)
					(thickness 0.15)
				)
			)
		)
		(property "License" "Apache-2.0"
			(at 297.18 191.77 0)
			(effects
				(font
					(size 1.27 1.27)
					(thickness 0.15)
				)
				(justify left bottom)
				(hide yes)
			)
		)
		(property "Author" "Antmicro"
			(at 297.18 194.31 0)
			(effects
				(font
					(size 1.27 1.27)
					(thickness 0.15)
				)
				(justify left bottom)
				(hide yes)
			)
		)
		(property "Tolerance" "1%"
			(at 297.18 176.53 0)
			(effects
				(font
					(size 1.27 1.27)
				)
				(justify left bottom)
				(hide yes)
			)
		)
		(pin "1"
		)
		(pin "2"
		)
		(instances
			(project "data-center-rdimm-ddr5-tester"
				(path ""
					(reference "R102")
					(unit 1)
				)
			)
		)
	)
	(symbol
		(lib_id "antmicropower:PWR_FLAG")
		(at 228.6 142.24 0)
		(unit 1)
		(exclude_from_sim no)
		(in_bom yes)
		(on_board yes)
		(dnp no)
		(fields_autoplaced yes)
		(property "Reference" "#FLG0106"
			(at 228.6 140.335 0)
			(effects
				(font
					(size 1.27 1.27)
				)
				(hide yes)
			)
		)
		(property "Value" "PWR_FLAG"
			(at 228.6 138.6642 0)
			(effects
				(font
					(size 1.27 1.27)
				)
			)
		)
		(property "Footprint" ""
			(at 228.6 142.24 0)
			(effects
				(font
					(size 1.27 1.27)
				)
				(hide yes)
			)
		)
		(property "Datasheet" ""
			(at 228.6 142.24 0)
			(effects
				(font
					(size 1.27 1.27)
				)
				(hide yes)
			)
		)
		(property "Description" ""
			(at 228.6 142.24 0)
			(effects
				(font
					(size 1.27 1.27)
				)
				(hide yes)
			)
		)
		(pin "1"
		)
		(instances
			(project "data-center-rdimm-ddr5-tester"
				(path ""
					(reference "#FLG0106")
					(unit 1)
				)
			)
		)
	)
	(symbol
		(lib_id "antmicroResistors0402:R_10k_0402")
		(at 317.5 176.53 0)
		(mirror y)
		(unit 1)
		(exclude_from_sim no)
		(in_bom yes)
		(on_board yes)
		(dnp no)
		(property "Reference" "R109"
			(at 321.31 175.26 0)
			(effects
				(font
					(size 1.27 1.27)
				)
			)
		)
		(property "Value" "R_10k_0402"
			(at 297.18 189.23 0)
			(effects
				(font
					(size 1.27 1.27)
					(thickness 0.15)
				)
				(justify left bottom)
				(hide yes)
			)
		)
		(property "Footprint" "antmicro-footprints:R_0402_1005Metric"
			(at 297.18 191.77 0)
			(effects
				(font
					(size 1.27 1.27)
					(thickness 0.15)
				)
				(justify left bottom)
				(hide yes)
			)
		)
		(property "Datasheet" "https://www.bourns.com/docs/product-datasheets/cr.pdf"
			(at 297.18 194.31 0)
			(effects
				(font
					(size 1.27 1.27)
					(thickness 0.15)
				)
				(justify left bottom)
				(hide yes)
			)
		)
		(property "Description" ""
			(at 317.5 176.53 0)
			(effects
				(font
					(size 1.27 1.27)
				)
				(hide yes)
			)
		)
		(property "Manufacturer" "Bourns"
			(at 297.18 199.39 0)
			(effects
				(font
					(size 1.27 1.27)
					(thickness 0.15)
				)
				(justify left bottom)
				(hide yes)
			)
		)
		(property "MPN" "CR0402-FX-1002GLF"
			(at 297.18 196.85 0)
			(effects
				(font
					(size 1.27 1.27)
					(thickness 0.15)
				)
				(justify left bottom)
				(hide yes)
			)
		)
		(property "Val" "10k"
			(at 310.515 175.26 0)
			(effects
				(font
					(size 1.27 1.27)
					(thickness 0.15)
				)
			)
		)
		(property "License" "Apache-2.0"
			(at 297.18 201.93 0)
			(effects
				(font
					(size 1.27 1.27)
					(thickness 0.15)
				)
				(justify left bottom)
				(hide yes)
			)
		)
		(property "Author" "Antmicro"
			(at 297.18 204.47 0)
			(effects
				(font
					(size 1.27 1.27)
					(thickness 0.15)
				)
				(justify left bottom)
				(hide yes)
			)
		)
		(property "Tolerance" "1%"
			(at 297.18 186.69 0)
			(effects
				(font
					(size 1.27 1.27)
				)
				(justify left bottom)
				(hide yes)
			)
		)
		(pin "1"
		)
		(pin "2"
		)
		(instances
			(project "data-center-rdimm-ddr5-tester"
				(path ""
					(reference "R109")
					(unit 1)
				)
			)
		)
	)
	(symbol
		(lib_id "antmicropower:GND")
		(at 326.39 238.76 0)
		(unit 1)
		(exclude_from_sim no)
		(in_bom yes)
		(on_board yes)
		(dnp no)
		(fields_autoplaced yes)
		(property "Reference" "#PWR0253"
			(at 326.39 245.11 0)
			(effects
				(font
					(size 1.27 1.27)
				)
				(hide yes)
			)
		)
		(property "Value" "GND"
			(at 324.485 243.205 0)
			(effects
				(font
					(size 1.27 1.27)
					(thickness 0.15)
				)
				(justify left bottom)
			)
		)
		(property "Footprint" ""
			(at 335.28 246.38 0)
			(effects
				(font
					(size 1.27 1.27)
					(thickness 0.15)
				)
				(justify left bottom)
				(hide yes)
			)
		)
		(property "Datasheet" ""
			(at 335.28 251.46 0)
			(effects
				(font
					(size 1.27 1.27)
					(thickness 0.15)
				)
				(justify left bottom)
				(hide yes)
			)
		)
		(property "Description" ""
			(at 326.39 238.76 0)
			(effects
				(font
					(size 1.27 1.27)
				)
				(hide yes)
			)
		)
		(property "Author" "Antmicro"
			(at 335.28 243.84 0)
			(effects
				(font
					(size 1.27 1.27)
					(thickness 0.15)
				)
				(justify left bottom)
				(hide yes)
			)
		)
		(property "License" "Apache-2.0"
			(at 335.28 246.38 0)
			(effects
				(font
					(size 1.27 1.27)
					(thickness 0.15)
				)
				(justify left bottom)
				(hide yes)
			)
		)
		(pin "1"
		)
		(instances
			(project "data-center-rdimm-ddr5-tester"
				(path ""
					(reference "#PWR0253")
					(unit 1)
				)
			)
		)
	)
	(symbol
		(lib_id "antmicropower:GND")
		(at 60.96 113.03 0)
		(unit 1)
		(exclude_from_sim no)
		(in_bom yes)
		(on_board yes)
		(dnp no)
		(property "Reference" "#PWR0406"
			(at 60.96 119.38 0)
			(effects
				(font
					(size 1.27 1.27)
				)
				(hide yes)
			)
		)
		(property "Value" "GND"
			(at 59.055 117.475 0)
			(effects
				(font
					(size 1.27 1.27)
					(thickness 0.15)
				)
				(justify left bottom)
			)
		)
		(property "Footprint" ""
			(at 69.85 120.65 0)
			(effects
				(font
					(size 1.27 1.27)
					(thickness 0.15)
				)
				(justify left bottom)
				(hide yes)
			)
		)
		(property "Datasheet" ""
			(at 69.85 125.73 0)
			(effects
				(font
					(size 1.27 1.27)
					(thickness 0.15)
				)
				(justify left bottom)
				(hide yes)
			)
		)
		(property "Description" ""
			(at 60.96 113.03 0)
			(effects
				(font
					(size 1.27 1.27)
				)
				(hide yes)
			)
		)
		(property "Author" "Antmicro"
			(at 69.85 118.11 0)
			(effects
				(font
					(size 1.27 1.27)
					(thickness 0.15)
				)
				(justify left bottom)
				(hide yes)
			)
		)
		(property "License" "Apache-2.0"
			(at 69.85 120.65 0)
			(effects
				(font
					(size 1.27 1.27)
					(thickness 0.15)
				)
				(justify left bottom)
				(hide yes)
			)
		)
		(pin "1"
		)
		(instances
			(project "data-center-rdimm-ddr5-tester"
				(path ""
					(reference "#PWR0406")
					(unit 1)
				)
			)
		)
	)
	(symbol
		(lib_id "antmicropower:+1V8")
		(at 300.99 158.75 0)
		(unit 1)
		(exclude_from_sim no)
		(in_bom yes)
		(on_board yes)
		(dnp no)
		(fields_autoplaced yes)
		(property "Reference" "#PWR0258"
			(at 316.23 161.29 0)
			(effects
				(font
					(size 1.27 1.27)
					(thickness 0.15)
				)
				(justify left bottom)
				(hide yes)
			)
		)
		(property "Value" "+1V8"
			(at 300.99 154.305 0)
			(effects
				(font
					(size 1.27 1.27)
					(thickness 0.15)
				)
			)
		)
		(property "Footprint" ""
			(at 316.23 166.37 0)
			(effects
				(font
					(size 1.27 1.27)
					(thickness 0.15)
				)
				(justify left bottom)
				(hide yes)
			)
		)
		(property "Datasheet" ""
			(at 316.23 168.91 0)
			(effects
				(font
					(size 1.27 1.27)
					(thickness 0.15)
				)
				(justify left bottom)
				(hide yes)
			)
		)
		(property "Description" ""
			(at 300.99 158.75 0)
			(effects
				(font
					(size 1.27 1.27)
				)
				(hide yes)
			)
		)
		(property "Author" "Antmicro"
			(at 316.23 163.83 0)
			(effects
				(font
					(size 1.27 1.27)
					(thickness 0.15)
				)
				(justify left bottom)
				(hide yes)
			)
		)
		(property "License" "Apache-2.0"
			(at 316.23 166.37 0)
			(effects
				(font
					(size 1.27 1.27)
					(thickness 0.15)
				)
				(justify left bottom)
				(hide yes)
			)
		)
		(pin "1"
		)
		(instances
			(project "data-center-rdimm-ddr5-tester"
				(path ""
					(reference "#PWR0258")
					(unit 1)
				)
			)
		)
	)
	(symbol
		(lib_id "antmicropower:GND")
		(at 175.26 134.62 0)
		(unit 1)
		(exclude_from_sim no)
		(in_bom yes)
		(on_board yes)
		(dnp no)
		(fields_autoplaced yes)
		(property "Reference" "#PWR0412"
			(at 175.26 140.97 0)
			(effects
				(font
					(size 1.27 1.27)
				)
				(hide yes)
			)
		)
		(property "Value" "GND"
			(at 173.355 139.065 0)
			(effects
				(font
					(size 1.27 1.27)
					(thickness 0.15)
				)
				(justify left bottom)
			)
		)
		(property "Footprint" ""
			(at 184.15 142.24 0)
			(effects
				(font
					(size 1.27 1.27)
					(thickness 0.15)
				)
				(justify left bottom)
				(hide yes)
			)
		)
		(property "Datasheet" ""
			(at 184.15 147.32 0)
			(effects
				(font
					(size 1.27 1.27)
					(thickness 0.15)
				)
				(justify left bottom)
				(hide yes)
			)
		)
		(property "Description" ""
			(at 175.26 134.62 0)
			(effects
				(font
					(size 1.27 1.27)
				)
				(hide yes)
			)
		)
		(property "Author" "Antmicro"
			(at 184.15 139.7 0)
			(effects
				(font
					(size 1.27 1.27)
					(thickness 0.15)
				)
				(justify left bottom)
				(hide yes)
			)
		)
		(property "License" "Apache-2.0"
			(at 184.15 142.24 0)
			(effects
				(font
					(size 1.27 1.27)
					(thickness 0.15)
				)
				(justify left bottom)
				(hide yes)
			)
		)
		(pin "1"
		)
		(instances
			(project "data-center-rdimm-ddr5-tester"
				(path ""
					(reference "#PWR0412")
					(unit 1)
				)
			)
		)
	)
	(symbol
		(lib_id "antmicroResistors0402:R_10k_0402")
		(at 317.5 163.83 0)
		(mirror y)
		(unit 1)
		(exclude_from_sim no)
		(in_bom yes)
		(on_board yes)
		(dnp no)
		(property "Reference" "R103"
			(at 321.31 162.56 0)
			(effects
				(font
					(size 1.27 1.27)
				)
			)
		)
		(property "Value" "R_10k_0402"
			(at 297.18 176.53 0)
			(effects
				(font
					(size 1.27 1.27)
					(thickness 0.15)
				)
				(justify left bottom)
				(hide yes)
			)
		)
		(property "Footprint" "antmicro-footprints:R_0402_1005Metric"
			(at 297.18 179.07 0)
			(effects
				(font
					(size 1.27 1.27)
					(thickness 0.15)
				)
				(justify left bottom)
				(hide yes)
			)
		)
		(property "Datasheet" "https://www.bourns.com/docs/product-datasheets/cr.pdf"
			(at 297.18 181.61 0)
			(effects
				(font
					(size 1.27 1.27)
					(thickness 0.15)
				)
				(justify left bottom)
				(hide yes)
			)
		)
		(property "Description" ""
			(at 317.5 163.83 0)
			(effects
				(font
					(size 1.27 1.27)
				)
				(hide yes)
			)
		)
		(property "Manufacturer" "Bourns"
			(at 297.18 186.69 0)
			(effects
				(font
					(size 1.27 1.27)
					(thickness 0.15)
				)
				(justify left bottom)
				(hide yes)
			)
		)
		(property "MPN" "CR0402-FX-1002GLF"
			(at 297.18 184.15 0)
			(effects
				(font
					(size 1.27 1.27)
					(thickness 0.15)
				)
				(justify left bottom)
				(hide yes)
			)
		)
		(property "Val" "10k"
			(at 310.515 162.56 0)
			(effects
				(font
					(size 1.27 1.27)
					(thickness 0.15)
				)
			)
		)
		(property "License" "Apache-2.0"
			(at 297.18 189.23 0)
			(effects
				(font
					(size 1.27 1.27)
					(thickness 0.15)
				)
				(justify left bottom)
				(hide yes)
			)
		)
		(property "Author" "Antmicro"
			(at 297.18 191.77 0)
			(effects
				(font
					(size 1.27 1.27)
					(thickness 0.15)
				)
				(justify left bottom)
				(hide yes)
			)
		)
		(property "Tolerance" "1%"
			(at 297.18 173.99 0)
			(effects
				(font
					(size 1.27 1.27)
				)
				(justify left bottom)
				(hide yes)
			)
		)
		(pin "1"
		)
		(pin "2"
		)
		(instances
			(project "data-center-rdimm-ddr5-tester"
				(path ""
					(reference "R103")
					(unit 1)
				)
			)
		)
	)
	(symbol
		(lib_id "antmicropower:+1V2")
		(at 245.11 100.33 0)
		(mirror y)
		(unit 1)
		(exclude_from_sim no)
		(in_bom yes)
		(on_board yes)
		(dnp no)
		(fields_autoplaced yes)
		(property "Reference" "#PWR0244"
			(at 245.11 104.14 0)
			(effects
				(font
					(size 1.27 1.27)
				)
				(hide yes)
			)
		)
		(property "Value" "+1V2"
			(at 245.11 95.25 0)
			(effects
				(font
					(size 1.27 1.27)
				)
			)
		)
		(property "Footprint" ""
			(at 245.11 100.33 0)
			(effects
				(font
					(size 1.27 1.27)
				)
				(hide yes)
			)
		)
		(property "Datasheet" ""
			(at 245.11 100.33 0)
			(effects
				(font
					(size 1.27 1.27)
				)
				(hide yes)
			)
		)
		(property "Description" ""
			(at 245.11 100.33 0)
			(effects
				(font
					(size 1.27 1.27)
				)
				(hide yes)
			)
		)
		(pin "1"
		)
		(instances
			(project "data-center-rdimm-ddr5-tester"
				(path ""
					(reference "#PWR0244")
					(unit 1)
				)
			)
		)
	)
	(symbol
		(lib_id "antmicroCapacitors0402:C_100n_0402")
		(at 337.82 237.49 90)
		(unit 1)
		(exclude_from_sim no)
		(in_bom yes)
		(on_board yes)
		(dnp no)
		(fields_autoplaced yes)
		(property "Reference" "C161"
			(at 340.1441 234.113 90)
			(effects
				(font
					(size 1.27 1.27)
					(thickness 0.15)
				)
				(justify right)
			)
		)
		(property "Value" "C_100n_0402"
			(at 347.98 217.17 0)
			(effects
				(font
					(size 1.27 1.27)
					(thickness 0.15)
				)
				(justify left bottom)
				(hide yes)
			)
		)
		(property "Footprint" "antmicro-footprints:C_0402_1005Metric"
			(at 350.52 217.17 0)
			(effects
				(font
					(size 1.27 1.27)
					(thickness 0.15)
				)
				(justify left bottom)
				(hide yes)
			)
		)
		(property "Datasheet" "https://www.murata.com/products/productdetail?partno=GRM155R61H104KE14%23"
			(at 353.06 217.17 0)
			(effects
				(font
					(size 1.27 1.27)
					(thickness 0.15)
				)
				(justify left bottom)
				(hide yes)
			)
		)
		(property "Description" ""
			(at 337.82 237.49 0)
			(effects
				(font
					(size 1.27 1.27)
				)
				(hide yes)
			)
		)
		(property "MPN" "GRM155R61H104KE14D"
			(at 355.6 217.17 0)
			(effects
				(font
					(size 1.27 1.27)
					(thickness 0.15)
				)
				(justify left bottom)
				(hide yes)
			)
		)
		(property "Manufacturer" "Murata"
			(at 358.14 217.17 0)
			(effects
				(font
					(size 1.27 1.27)
					(thickness 0.15)
				)
				(justify left bottom)
				(hide yes)
			)
		)
		(property "License" "Apache-2.0"
			(at 360.68 217.17 0)
			(effects
				(font
					(size 1.27 1.27)
					(thickness 0.15)
				)
				(justify left bottom)
				(hide yes)
			)
		)
		(property "Author" "Antmicro"
			(at 363.22 217.17 0)
			(effects
				(font
					(size 1.27 1.27)
					(thickness 0.15)
				)
				(justify left bottom)
				(hide yes)
			)
		)
		(property "Val" "100n"
			(at 340.1441 236.6367 90)
			(effects
				(font
					(size 1.27 1.27)
					(thickness 0.15)
				)
				(justify right)
			)
		)
		(property "Voltage" "50V"
			(at 365.76 217.17 0)
			(effects
				(font
					(size 1.27 1.27)
				)
				(justify left bottom)
				(hide yes)
			)
		)
		(property "Dielectric" "X5R"
			(at 368.3 217.17 0)
			(effects
				(font
					(size 1.27 1.27)
				)
				(justify left bottom)
				(hide yes)
			)
		)
		(pin "1"
		)
		(pin "2"
		)
		(instances
			(project "data-center-rdimm-ddr5-tester"
				(path ""
					(reference "C161")
					(unit 1)
				)
			)
		)
	)
	(symbol
		(lib_id "antmicropower:+3V3")
		(at 361.95 76.2 0)
		(unit 1)
		(exclude_from_sim no)
		(in_bom yes)
		(on_board yes)
		(dnp no)
		(property "Reference" "#PWR0464"
			(at 361.95 80.01 0)
			(effects
				(font
					(size 1.27 1.27)
				)
				(hide yes)
			)
		)
		(property "Value" "+3V3"
			(at 358.775 73.66 0)
			(effects
				(font
					(size 1.27 1.27)
					(thickness 0.15)
				)
				(justify left bottom)
			)
		)
		(property "Footprint" ""
			(at 377.19 83.82 0)
			(effects
				(font
					(size 1.27 1.27)
					(thickness 0.15)
				)
				(justify left bottom)
				(hide yes)
			)
		)
		(property "Datasheet" ""
			(at 377.19 86.36 0)
			(effects
				(font
					(size 1.27 1.27)
					(thickness 0.15)
				)
				(justify left bottom)
				(hide yes)
			)
		)
		(property "Description" ""
			(at 361.95 76.2 0)
			(effects
				(font
					(size 1.27 1.27)
				)
				(hide yes)
			)
		)
		(property "Author" "Antmicro"
			(at 377.19 78.74 0)
			(effects
				(font
					(size 1.27 1.27)
					(thickness 0.15)
				)
				(justify left bottom)
				(hide yes)
			)
		)
		(property "License" "Apache-2.0"
			(at 377.19 81.28 0)
			(effects
				(font
					(size 1.27 1.27)
					(thickness 0.15)
				)
				(justify left bottom)
				(hide yes)
			)
		)
		(pin "1"
		)
		(instances
			(project "data-center-rdimm-ddr5-tester"
				(path ""
					(reference "#PWR0464")
					(unit 1)
				)
			)
		)
	)
	(symbol
		(lib_id "antmicropower:GND")
		(at 85.09 113.03 0)
		(unit 1)
		(exclude_from_sim no)
		(in_bom yes)
		(on_board yes)
		(dnp no)
		(property "Reference" "#PWR0404"
			(at 85.09 119.38 0)
			(effects
				(font
					(size 1.27 1.27)
				)
				(hide yes)
			)
		)
		(property "Value" "GND"
			(at 83.185 117.475 0)
			(effects
				(font
					(size 1.27 1.27)
					(thickness 0.15)
				)
				(justify left bottom)
			)
		)
		(property "Footprint" ""
			(at 93.98 120.65 0)
			(effects
				(font
					(size 1.27 1.27)
					(thickness 0.15)
				)
				(justify left bottom)
				(hide yes)
			)
		)
		(property "Datasheet" ""
			(at 93.98 125.73 0)
			(effects
				(font
					(size 1.27 1.27)
					(thickness 0.15)
				)
				(justify left bottom)
				(hide yes)
			)
		)
		(property "Description" ""
			(at 85.09 113.03 0)
			(effects
				(font
					(size 1.27 1.27)
				)
				(hide yes)
			)
		)
		(property "Author" "Antmicro"
			(at 93.98 118.11 0)
			(effects
				(font
					(size 1.27 1.27)
					(thickness 0.15)
				)
				(justify left bottom)
				(hide yes)
			)
		)
		(property "License" "Apache-2.0"
			(at 93.98 120.65 0)
			(effects
				(font
					(size 1.27 1.27)
					(thickness 0.15)
				)
				(justify left bottom)
				(hide yes)
			)
		)
		(pin "1"
		)
		(instances
			(project "data-center-rdimm-ddr5-tester"
				(path ""
					(reference "#PWR0404")
					(unit 1)
				)
			)
		)
	)
	(symbol
		(lib_id "antmicropower:GND")
		(at 215.9 114.3 0)
		(mirror y)
		(unit 1)
		(exclude_from_sim no)
		(in_bom yes)
		(on_board yes)
		(dnp no)
		(fields_autoplaced yes)
		(property "Reference" "#PWR0420"
			(at 215.9 120.65 0)
			(effects
				(font
					(size 1.27 1.27)
				)
				(hide yes)
			)
		)
		(property "Value" "GND"
			(at 217.805 118.745 0)
			(effects
				(font
					(size 1.27 1.27)
					(thickness 0.15)
				)
				(justify left bottom)
			)
		)
		(property "Footprint" ""
			(at 207.01 121.92 0)
			(effects
				(font
					(size 1.27 1.27)
					(thickness 0.15)
				)
				(justify left bottom)
				(hide yes)
			)
		)
		(property "Datasheet" ""
			(at 207.01 127 0)
			(effects
				(font
					(size 1.27 1.27)
					(thickness 0.15)
				)
				(justify left bottom)
				(hide yes)
			)
		)
		(property "Description" ""
			(at 215.9 114.3 0)
			(effects
				(font
					(size 1.27 1.27)
				)
				(hide yes)
			)
		)
		(property "Author" "Antmicro"
			(at 207.01 119.38 0)
			(effects
				(font
					(size 1.27 1.27)
					(thickness 0.15)
				)
				(justify left bottom)
				(hide yes)
			)
		)
		(property "License" "Apache-2.0"
			(at 207.01 121.92 0)
			(effects
				(font
					(size 1.27 1.27)
					(thickness 0.15)
				)
				(justify left bottom)
				(hide yes)
			)
		)
		(pin "1"
		)
		(instances
			(project "data-center-rdimm-ddr5-tester"
				(path ""
					(reference "#PWR0420")
					(unit 1)
				)
			)
		)
	)
	(symbol
		(lib_id "antmicroCapacitors0402:C_100n_0402")
		(at 321.31 85.09 270)
		(unit 1)
		(exclude_from_sim no)
		(in_bom yes)
		(on_board yes)
		(dnp no)
		(fields_autoplaced yes)
		(property "Reference" "C234"
			(at 323.85 86.3662 90)
			(effects
				(font
					(size 1.27 1.27)
				)
				(justify left)
			)
		)
		(property "Value" "C_100n_0402"
			(at 311.15 105.41 0)
			(effects
				(font
					(size 1.27 1.27)
					(thickness 0.15)
				)
				(justify left bottom)
				(hide yes)
			)
		)
		(property "Footprint" "antmicro-footprints:C_0402_1005Metric"
			(at 308.61 105.41 0)
			(effects
				(font
					(size 1.27 1.27)
					(thickness 0.15)
				)
				(justify left bottom)
				(hide yes)
			)
		)
		(property "Datasheet" "https://www.murata.com/products/productdetail?partno=GRM155R61H104KE14%23"
			(at 306.07 105.41 0)
			(effects
				(font
					(size 1.27 1.27)
					(thickness 0.15)
				)
				(justify left bottom)
				(hide yes)
			)
		)
		(property "Description" ""
			(at 321.31 85.09 0)
			(effects
				(font
					(size 1.27 1.27)
				)
				(hide yes)
			)
		)
		(property "Manufacturer" "Murata"
			(at 300.99 105.41 0)
			(effects
				(font
					(size 1.27 1.27)
					(thickness 0.15)
				)
				(justify left bottom)
				(hide yes)
			)
		)
		(property "MPN" "GRM155R61H104KE14D"
			(at 303.53 105.41 0)
			(effects
				(font
					(size 1.27 1.27)
					(thickness 0.15)
				)
				(justify left bottom)
				(hide yes)
			)
		)
		(property "Val" "100n"
			(at 323.85 88.9063 90)
			(effects
				(font
					(size 1.27 1.27)
					(thickness 0.15)
				)
				(justify left)
			)
		)
		(property "License" "Apache-2.0"
			(at 298.45 105.41 0)
			(effects
				(font
					(size 1.27 1.27)
					(thickness 0.15)
				)
				(justify left bottom)
				(hide yes)
			)
		)
		(property "Author" "Antmicro"
			(at 295.91 105.41 0)
			(effects
				(font
					(size 1.27 1.27)
					(thickness 0.15)
				)
				(justify left bottom)
				(hide yes)
			)
		)
		(property "Voltage" "50V"
			(at 293.37 105.41 0)
			(effects
				(font
					(size 1.27 1.27)
				)
				(justify left bottom)
				(hide yes)
			)
		)
		(property "Dielectric" "X5R"
			(at 290.83 105.41 0)
			(effects
				(font
					(size 1.27 1.27)
				)
				(justify left bottom)
				(hide yes)
			)
		)
		(pin "1"
		)
		(pin "2"
		)
		(instances
			(project "data-center-rdimm-ddr5-tester"
				(path ""
					(reference "C234")
					(unit 1)
				)
			)
		)
	)
	(symbol
		(lib_id "antmicroFerriteBeadsandChips:FB_120Z_2A_Murata-BLM18PG_0603")
		(at 242.57 127 0)
		(mirror y)
		(unit 1)
		(exclude_from_sim no)
		(in_bom yes)
		(on_board yes)
		(dnp no)
		(fields_autoplaced yes)
		(property "Reference" "FB4"
			(at 240.0681 121.605 0)
			(effects
				(font
					(size 1.27 1.27)
					(thickness 0.15)
				)
			)
		)
		(property "Value" "FB_120Z_2A_Murata-BLM18PG_0603"
			(at 227.33 129.54 0)
			(effects
				(font
					(size 1.27 1.27)
					(thickness 0.15)
				)
				(justify left bottom)
				(hide yes)
			)
		)
		(property "Footprint" "antmicro-footprints:FB_0603_1608Metric"
			(at 227.33 134.62 0)
			(effects
				(font
					(size 1.27 1.27)
					(thickness 0.15)
				)
				(justify left bottom)
				(hide yes)
			)
		)
		(property "Datasheet" "https://www.murata.com/en-us/products/productdata/8796738650142/ENFA0003.pdf"
			(at 227.33 137.16 0)
			(effects
				(font
					(size 1.27 1.27)
					(thickness 0.15)
				)
				(justify left bottom)
				(hide yes)
			)
		)
		(property "Description" ""
			(at 242.57 127 0)
			(effects
				(font
					(size 1.27 1.27)
				)
				(hide yes)
			)
		)
		(property "Val" "120Z/2A"
			(at 240.0681 124.1353 0)
			(effects
				(font
					(size 1.27 1.27)
				)
			)
		)
		(property "MPN" "BLM18PG121SN1D"
			(at 227.33 139.7 0)
			(effects
				(font
					(size 1.27 1.27)
					(thickness 0.15)
				)
				(justify left bottom)
				(hide yes)
			)
		)
		(property "Manufacturer" "Murata"
			(at 227.33 142.24 0)
			(effects
				(font
					(size 1.27 1.27)
					(thickness 0.15)
				)
				(justify left bottom)
				(hide yes)
			)
		)
		(property "Author" "Antmicro"
			(at 227.33 144.78 0)
			(effects
				(font
					(size 1.27 1.27)
					(thickness 0.15)
				)
				(justify left bottom)
				(hide yes)
			)
		)
		(property "License" "Apache-2.0"
			(at 227.33 147.32 0)
			(effects
				(font
					(size 1.27 1.27)
					(thickness 0.15)
				)
				(justify left bottom)
				(hide yes)
			)
		)
		(pin "1"
		)
		(pin "2"
		)
		(instances
			(project "data-center-rdimm-ddr5-tester"
				(path ""
					(reference "FB4")
					(unit 1)
				)
			)
		)
	)
	(symbol
		(lib_id "antmicropower:+3V3")
		(at 25.4 100.33 0)
		(unit 1)
		(exclude_from_sim no)
		(in_bom yes)
		(on_board yes)
		(dnp no)
		(fields_autoplaced yes)
		(property "Reference" "#PWR0240"
			(at 25.4 104.14 0)
			(effects
				(font
					(size 1.27 1.27)
				)
				(hide yes)
			)
		)
		(property "Value" "+3V3"
			(at 22.225 97.79 0)
			(effects
				(font
					(size 1.27 1.27)
					(thickness 0.15)
				)
				(justify left bottom)
			)
		)
		(property "Footprint" ""
			(at 40.64 107.95 0)
			(effects
				(font
					(size 1.27 1.27)
					(thickness 0.15)
				)
				(justify left bottom)
				(hide yes)
			)
		)
		(property "Datasheet" ""
			(at 40.64 110.49 0)
			(effects
				(font
					(size 1.27 1.27)
					(thickness 0.15)
				)
				(justify left bottom)
				(hide yes)
			)
		)
		(property "Description" ""
			(at 25.4 100.33 0)
			(effects
				(font
					(size 1.27 1.27)
				)
				(hide yes)
			)
		)
		(property "Author" "Antmicro"
			(at 40.64 102.87 0)
			(effects
				(font
					(size 1.27 1.27)
					(thickness 0.15)
				)
				(justify left bottom)
				(hide yes)
			)
		)
		(property "License" "Apache-2.0"
			(at 40.64 105.41 0)
			(effects
				(font
					(size 1.27 1.27)
					(thickness 0.15)
				)
				(justify left bottom)
				(hide yes)
			)
		)
		(pin "1"
		)
		(instances
			(project "data-center-rdimm-ddr5-tester"
				(path ""
					(reference "#PWR0240")
					(unit 1)
				)
			)
		)
	)
	(symbol
		(lib_id "antmicropower:GND")
		(at 191.77 114.3 0)
		(mirror y)
		(unit 1)
		(exclude_from_sim no)
		(in_bom yes)
		(on_board yes)
		(dnp no)
		(fields_autoplaced yes)
		(property "Reference" "#PWR0419"
			(at 191.77 120.65 0)
			(effects
				(font
					(size 1.27 1.27)
				)
				(hide yes)
			)
		)
		(property "Value" "GND"
			(at 193.675 118.745 0)
			(effects
				(font
					(size 1.27 1.27)
					(thickness 0.15)
				)
				(justify left bottom)
			)
		)
		(property "Footprint" ""
			(at 182.88 121.92 0)
			(effects
				(font
					(size 1.27 1.27)
					(thickness 0.15)
				)
				(justify left bottom)
				(hide yes)
			)
		)
		(property "Datasheet" ""
			(at 182.88 127 0)
			(effects
				(font
					(size 1.27 1.27)
					(thickness 0.15)
				)
				(justify left bottom)
				(hide yes)
			)
		)
		(property "Description" ""
			(at 191.77 114.3 0)
			(effects
				(font
					(size 1.27 1.27)
				)
				(hide yes)
			)
		)
		(property "Author" "Antmicro"
			(at 182.88 119.38 0)
			(effects
				(font
					(size 1.27 1.27)
					(thickness 0.15)
				)
				(justify left bottom)
				(hide yes)
			)
		)
		(property "License" "Apache-2.0"
			(at 182.88 121.92 0)
			(effects
				(font
					(size 1.27 1.27)
					(thickness 0.15)
				)
				(justify left bottom)
				(hide yes)
			)
		)
		(pin "1"
		)
		(instances
			(project "data-center-rdimm-ddr5-tester"
				(path ""
					(reference "#PWR0419")
					(unit 1)
				)
			)
		)
	)
	(symbol
		(lib_id "antmicroCapacitors0402:C_18p_0402")
		(at 100.33 208.28 90)
		(unit 1)
		(exclude_from_sim no)
		(in_bom yes)
		(on_board yes)
		(dnp no)
		(fields_autoplaced yes)
		(property "Reference" "C163"
			(at 102.6541 204.903 90)
			(effects
				(font
					(size 1.27 1.27)
					(thickness 0.15)
				)
				(justify right)
			)
		)
		(property "Value" "C_18p_0402"
			(at 110.49 187.96 0)
			(effects
				(font
					(size 1.27 1.27)
					(thickness 0.15)
				)
				(justify left bottom)
				(hide yes)
			)
		)
		(property "Footprint" "antmicro-footprints:C_0402_1005Metric"
			(at 113.03 187.96 0)
			(effects
				(font
					(size 1.27 1.27)
					(thickness 0.15)
				)
				(justify left bottom)
				(hide yes)
			)
		)
		(property "Datasheet" "https://product.samsungsem.com/mlcc/CL05C180JB51PN.do"
			(at 115.57 187.96 0)
			(effects
				(font
					(size 1.27 1.27)
					(thickness 0.15)
				)
				(justify left bottom)
				(hide yes)
			)
		)
		(property "Description" ""
			(at 100.33 208.28 0)
			(effects
				(font
					(size 1.27 1.27)
				)
				(hide yes)
			)
		)
		(property "MPN" "CL05C180JB51PNC"
			(at 118.11 187.96 0)
			(effects
				(font
					(size 1.27 1.27)
					(thickness 0.15)
				)
				(justify left bottom)
				(hide yes)
			)
		)
		(property "Manufacturer" "Samsung Electro-Mechanics"
			(at 120.65 187.96 0)
			(effects
				(font
					(size 1.27 1.27)
					(thickness 0.15)
				)
				(justify left bottom)
				(hide yes)
			)
		)
		(property "License" "Apache-2.0"
			(at 123.19 187.96 0)
			(effects
				(font
					(size 1.27 1.27)
					(thickness 0.15)
				)
				(justify left bottom)
				(hide yes)
			)
		)
		(property "Author" "Antmicro"
			(at 125.73 187.96 0)
			(effects
				(font
					(size 1.27 1.27)
					(thickness 0.15)
				)
				(justify left bottom)
				(hide yes)
			)
		)
		(property "Val" "18p"
			(at 102.6541 207.4267 90)
			(effects
				(font
					(size 1.27 1.27)
					(thickness 0.15)
				)
				(justify right)
			)
		)
		(property "Voltage" ""
			(at 128.27 187.96 0)
			(effects
				(font
					(size 1.27 1.27)
				)
				(justify left bottom)
				(hide yes)
			)
		)
		(property "Dielectric" ""
			(at 130.81 187.96 0)
			(effects
				(font
					(size 1.27 1.27)
				)
				(justify left bottom)
				(hide yes)
			)
		)
		(pin "1"
		)
		(pin "2"
		)
		(instances
			(project "data-center-rdimm-ddr5-tester"
				(path ""
					(reference "C163")
					(unit 1)
				)
			)
		)
	)
	(symbol
		(lib_id "antmicroResistors0402:R_10k_0402")
		(at 71.12 140.97 180)
		(unit 1)
		(exclude_from_sim no)
		(in_bom yes)
		(on_board yes)
		(dnp no)
		(property "Reference" "R111"
			(at 74.93 139.7 0)
			(effects
				(font
					(size 1.27 1.27)
				)
			)
		)
		(property "Value" "R_10k_0402"
			(at 50.8 128.27 0)
			(effects
				(font
					(size 1.27 1.27)
					(thickness 0.15)
				)
				(justify left bottom)
				(hide yes)
			)
		)
		(property "Footprint" "antmicro-footprints:R_0402_1005Metric"
			(at 50.8 125.73 0)
			(effects
				(font
					(size 1.27 1.27)
					(thickness 0.15)
				)
				(justify left bottom)
				(hide yes)
			)
		)
		(property "Datasheet" "https://www.bourns.com/docs/product-datasheets/cr.pdf"
			(at 50.8 123.19 0)
			(effects
				(font
					(size 1.27 1.27)
					(thickness 0.15)
				)
				(justify left bottom)
				(hide yes)
			)
		)
		(property "Description" ""
			(at 71.12 140.97 0)
			(effects
				(font
					(size 1.27 1.27)
				)
				(hide yes)
			)
		)
		(property "Manufacturer" "Bourns"
			(at 50.8 118.11 0)
			(effects
				(font
					(size 1.27 1.27)
					(thickness 0.15)
				)
				(justify left bottom)
				(hide yes)
			)
		)
		(property "MPN" "CR0402-FX-1002GLF"
			(at 50.8 120.65 0)
			(effects
				(font
					(size 1.27 1.27)
					(thickness 0.15)
				)
				(justify left bottom)
				(hide yes)
			)
		)
		(property "Val" "10k"
			(at 64.135 139.7 0)
			(effects
				(font
					(size 1.27 1.27)
					(thickness 0.15)
				)
			)
		)
		(property "License" "Apache-2.0"
			(at 50.8 115.57 0)
			(effects
				(font
					(size 1.27 1.27)
					(thickness 0.15)
				)
				(justify left bottom)
				(hide yes)
			)
		)
		(property "Author" "Antmicro"
			(at 50.8 113.03 0)
			(effects
				(font
					(size 1.27 1.27)
					(thickness 0.15)
				)
				(justify left bottom)
				(hide yes)
			)
		)
		(property "Tolerance" "1%"
			(at 50.8 130.81 0)
			(effects
				(font
					(size 1.27 1.27)
				)
				(justify left bottom)
				(hide yes)
			)
		)
		(pin "1"
		)
		(pin "2"
		)
		(instances
			(project "data-center-rdimm-ddr5-tester"
				(path ""
					(reference "R111")
					(unit 1)
				)
			)
		)
	)
	(symbol
		(lib_id "antmicroResonators:Resonator_25MHz_ABM8G")
		(at 97.79 201.93 0)
		(mirror y)
		(unit 1)
		(exclude_from_sim no)
		(in_bom yes)
		(on_board yes)
		(dnp no)
		(fields_autoplaced yes)
		(property "Reference" "Y2"
			(at 93.98 195.705 0)
			(effects
				(font
					(size 1.27 1.27)
					(thickness 0.15)
				)
			)
		)
		(property "Value" "Resonator_25MHz_ABM8G"
			(at 82.55 214.63 0)
			(effects
				(font
					(size 1.27 1.27)
					(thickness 0.15)
				)
				(justify left bottom)
				(hide yes)
			)
		)
		(property "Footprint" "antmicro-footprints:Resonator_SMD_Abracon_ABM8G_3.2x2.5mm"
			(at 82.55 217.17 0)
			(effects
				(font
					(size 1.27 1.27)
					(thickness 0.15)
				)
				(justify left bottom)
				(hide yes)
			)
		)
		(property "Datasheet" "https://abracon.com/Resonators/ABM8G.pdf"
			(at 82.55 219.71 0)
			(effects
				(font
					(size 1.27 1.27)
					(thickness 0.15)
				)
				(justify left bottom)
				(hide yes)
			)
		)
		(property "Description" ""
			(at 97.79 201.93 0)
			(effects
				(font
					(size 1.27 1.27)
				)
				(hide yes)
			)
		)
		(property "MPN" "ABM8G-25.000MHZ-18-D2Y-T3"
			(at 82.55 209.55 0)
			(effects
				(font
					(size 1.27 1.27)
					(thickness 0.15)
				)
				(justify left bottom)
				(hide yes)
			)
		)
		(property "Manufacturer" "Abracon"
			(at 82.55 222.25 0)
			(effects
				(font
					(size 1.27 1.27)
					(thickness 0.15)
				)
				(justify left bottom)
				(hide yes)
			)
		)
		(property "Author" "Antmicro"
			(at 82.55 224.79 0)
			(effects
				(font
					(size 1.27 1.27)
					(thickness 0.15)
				)
				(justify left bottom)
				(hide yes)
			)
		)
		(property "License" "Apache-2.0"
			(at 82.55 227.33 0)
			(effects
				(font
					(size 1.27 1.27)
					(thickness 0.15)
				)
				(justify left bottom)
				(hide yes)
			)
		)
		(property "Val" "25 MHz"
			(at 93.98 198.2287 0)
			(effects
				(font
					(size 1.27 1.27)
					(thickness 0.15)
				)
			)
		)
		(pin "1"
		)
		(pin "2"
		)
		(pin "3"
		)
		(pin "4"
		)
		(instances
			(project "data-center-rdimm-ddr5-tester"
				(path ""
					(reference "Y2")
					(unit 1)
				)
			)
		)
	)
	(symbol
		(lib_id "antmicroResistors0402:R_330R_0402")
		(at 311.15 90.17 90)
		(unit 1)
		(exclude_from_sim no)
		(in_bom yes)
		(on_board yes)
		(dnp no)
		(fields_autoplaced yes)
		(property "Reference" "R193"
			(at 313.69 86.3599 90)
			(effects
				(font
					(size 1.27 1.27)
				)
				(justify right)
			)
		)
		(property "Value" "R_330R_0402"
			(at 323.85 69.85 0)
			(effects
				(font
					(size 1.27 1.27)
					(thickness 0.15)
				)
				(justify left bottom)
				(hide yes)
			)
		)
		(property "Footprint" "antmicro-footprints:R_0402_1005Metric"
			(at 326.39 69.85 0)
			(effects
				(font
					(size 1.27 1.27)
					(thickness 0.15)
				)
				(justify left bottom)
				(hide yes)
			)
		)
		(property "Datasheet" "https://www.bourns.com/docs/product-datasheets/cr.pdf"
			(at 328.93 69.85 0)
			(effects
				(font
					(size 1.27 1.27)
					(thickness 0.15)
				)
				(justify left bottom)
				(hide yes)
			)
		)
		(property "Description" ""
			(at 311.15 90.17 0)
			(effects
				(font
					(size 1.27 1.27)
				)
				(hide yes)
			)
		)
		(property "Manufacturer" "Bourns"
			(at 334.01 69.85 0)
			(effects
				(font
					(size 1.27 1.27)
					(thickness 0.15)
				)
				(justify left bottom)
				(hide yes)
			)
		)
		(property "MPN" "CR0402-FX-3300GLF"
			(at 331.47 69.85 0)
			(effects
				(font
					(size 1.27 1.27)
					(thickness 0.15)
				)
				(justify left bottom)
				(hide yes)
			)
		)
		(property "Val" "330R"
			(at 313.69 88.9 90)
			(effects
				(font
					(size 1.27 1.27)
					(thickness 0.15)
				)
				(justify right)
			)
		)
		(property "License" "Apache-2.0"
			(at 336.55 69.85 0)
			(effects
				(font
					(size 1.27 1.27)
					(thickness 0.15)
				)
				(justify left bottom)
				(hide yes)
			)
		)
		(property "Author" "Antmicro"
			(at 339.09 69.85 0)
			(effects
				(font
					(size 1.27 1.27)
					(thickness 0.15)
				)
				(justify left bottom)
				(hide yes)
			)
		)
		(property "Tolerance" "1%"
			(at 321.31 69.85 0)
			(effects
				(font
					(size 1.27 1.27)
				)
				(justify left bottom)
				(hide yes)
			)
		)
		(pin "1"
		)
		(pin "2"
		)
		(instances
			(project "data-center-rdimm-ddr5-tester"
				(path ""
					(reference "R193")
					(unit 1)
				)
			)
		)
	)
	(symbol
		(lib_id "antmicroResistors0402:R_10k_0402")
		(at 317.5 171.45 0)
		(mirror y)
		(unit 1)
		(exclude_from_sim no)
		(in_bom no)
		(on_board yes)
		(dnp yes)
		(property "Reference" "R106"
			(at 321.31 170.18 0)
			(effects
				(font
					(size 1.27 1.27)
				)
			)
		)
		(property "Value" "R_10k_0402"
			(at 297.18 184.15 0)
			(effects
				(font
					(size 1.27 1.27)
					(thickness 0.15)
				)
				(justify left bottom)
				(hide yes)
			)
		)
		(property "Footprint" "antmicro-footprints:R_0402_1005Metric"
			(at 297.18 186.69 0)
			(effects
				(font
					(size 1.27 1.27)
					(thickness 0.15)
				)
				(justify left bottom)
				(hide yes)
			)
		)
		(property "Datasheet" "https://www.bourns.com/docs/product-datasheets/cr.pdf"
			(at 297.18 189.23 0)
			(effects
				(font
					(size 1.27 1.27)
					(thickness 0.15)
				)
				(justify left bottom)
				(hide yes)
			)
		)
		(property "Description" ""
			(at 317.5 171.45 0)
			(effects
				(font
					(size 1.27 1.27)
				)
				(hide yes)
			)
		)
		(property "Manufacturer" "Bourns"
			(at 297.18 194.31 0)
			(effects
				(font
					(size 1.27 1.27)
					(thickness 0.15)
				)
				(justify left bottom)
				(hide yes)
			)
		)
		(property "MPN" "CR0402-FX-1002GLF"
			(at 297.18 191.77 0)
			(effects
				(font
					(size 1.27 1.27)
					(thickness 0.15)
				)
				(justify left bottom)
				(hide yes)
			)
		)
		(property "Val" "10k"
			(at 310.515 170.18 0)
			(effects
				(font
					(size 1.27 1.27)
					(thickness 0.15)
				)
			)
		)
		(property "License" "Apache-2.0"
			(at 297.18 196.85 0)
			(effects
				(font
					(size 1.27 1.27)
					(thickness 0.15)
				)
				(justify left bottom)
				(hide yes)
			)
		)
		(property "Author" "Antmicro"
			(at 297.18 199.39 0)
			(effects
				(font
					(size 1.27 1.27)
					(thickness 0.15)
				)
				(justify left bottom)
				(hide yes)
			)
		)
		(property "Tolerance" "1%"
			(at 297.18 181.61 0)
			(effects
				(font
					(size 1.27 1.27)
				)
				(justify left bottom)
				(hide yes)
			)
		)
		(pin "1"
		)
		(pin "2"
		)
		(instances
			(project "data-center-rdimm-ddr5-tester"
				(path ""
					(reference "R106")
					(unit 1)
				)
			)
		)
	)
	(symbol
		(lib_id "antmicroResistors0402:R_10k_0402")
		(at 317.5 168.91 0)
		(mirror y)
		(unit 1)
		(exclude_from_sim no)
		(in_bom no)
		(on_board yes)
		(dnp yes)
		(property "Reference" "R101"
			(at 321.31 167.64 0)
			(effects
				(font
					(size 1.27 1.27)
				)
			)
		)
		(property "Value" "R_10k_0402"
			(at 297.18 181.61 0)
			(effects
				(font
					(size 1.27 1.27)
					(thickness 0.15)
				)
				(justify left bottom)
				(hide yes)
			)
		)
		(property "Footprint" "antmicro-footprints:R_0402_1005Metric"
			(at 297.18 184.15 0)
			(effects
				(font
					(size 1.27 1.27)
					(thickness 0.15)
				)
				(justify left bottom)
				(hide yes)
			)
		)
		(property "Datasheet" "https://www.bourns.com/docs/product-datasheets/cr.pdf"
			(at 297.18 186.69 0)
			(effects
				(font
					(size 1.27 1.27)
					(thickness 0.15)
				)
				(justify left bottom)
				(hide yes)
			)
		)
		(property "Description" ""
			(at 317.5 168.91 0)
			(effects
				(font
					(size 1.27 1.27)
				)
				(hide yes)
			)
		)
		(property "Manufacturer" "Bourns"
			(at 297.18 191.77 0)
			(effects
				(font
					(size 1.27 1.27)
					(thickness 0.15)
				)
				(justify left bottom)
				(hide yes)
			)
		)
		(property "MPN" "CR0402-FX-1002GLF"
			(at 297.18 189.23 0)
			(effects
				(font
					(size 1.27 1.27)
					(thickness 0.15)
				)
				(justify left bottom)
				(hide yes)
			)
		)
		(property "Val" "10k"
			(at 310.515 167.64 0)
			(effects
				(font
					(size 1.27 1.27)
					(thickness 0.15)
				)
			)
		)
		(property "License" "Apache-2.0"
			(at 297.18 194.31 0)
			(effects
				(font
					(size 1.27 1.27)
					(thickness 0.15)
				)
				(justify left bottom)
				(hide yes)
			)
		)
		(property "Author" "Antmicro"
			(at 297.18 196.85 0)
			(effects
				(font
					(size 1.27 1.27)
					(thickness 0.15)
				)
				(justify left bottom)
				(hide yes)
			)
		)
		(property "Tolerance" "1%"
			(at 297.18 179.07 0)
			(effects
				(font
					(size 1.27 1.27)
				)
				(justify left bottom)
				(hide yes)
			)
		)
		(pin "1"
		)
		(pin "2"
		)
		(instances
			(project "data-center-rdimm-ddr5-tester"
				(path ""
					(reference "R101")
					(unit 1)
				)
			)
		)
	)
	(symbol
		(lib_id "antmicropower:GND")
		(at 337.82 238.76 0)
		(unit 1)
		(exclude_from_sim no)
		(in_bom yes)
		(on_board yes)
		(dnp no)
		(fields_autoplaced yes)
		(property "Reference" "#PWR0255"
			(at 337.82 245.11 0)
			(effects
				(font
					(size 1.27 1.27)
				)
				(hide yes)
			)
		)
		(property "Value" "GND"
			(at 335.915 243.205 0)
			(effects
				(font
					(size 1.27 1.27)
					(thickness 0.15)
				)
				(justify left bottom)
			)
		)
		(property "Footprint" ""
			(at 346.71 246.38 0)
			(effects
				(font
					(size 1.27 1.27)
					(thickness 0.15)
				)
				(justify left bottom)
				(hide yes)
			)
		)
		(property "Datasheet" ""
			(at 346.71 251.46 0)
			(effects
				(font
					(size 1.27 1.27)
					(thickness 0.15)
				)
				(justify left bottom)
				(hide yes)
			)
		)
		(property "Description" ""
			(at 337.82 238.76 0)
			(effects
				(font
					(size 1.27 1.27)
				)
				(hide yes)
			)
		)
		(property "Author" "Antmicro"
			(at 346.71 243.84 0)
			(effects
				(font
					(size 1.27 1.27)
					(thickness 0.15)
				)
				(justify left bottom)
				(hide yes)
			)
		)
		(property "License" "Apache-2.0"
			(at 346.71 246.38 0)
			(effects
				(font
					(size 1.27 1.27)
					(thickness 0.15)
				)
				(justify left bottom)
				(hide yes)
			)
		)
		(pin "1"
		)
		(instances
			(project "data-center-rdimm-ddr5-tester"
				(path ""
					(reference "#PWR0255")
					(unit 1)
				)
			)
		)
	)
	(symbol
		(lib_id "antmicroResistors0402:R_10k_0402")
		(at 317.5 173.99 0)
		(mirror y)
		(unit 1)
		(exclude_from_sim no)
		(in_bom yes)
		(on_board yes)
		(dnp no)
		(property "Reference" "R108"
			(at 321.31 172.72 0)
			(effects
				(font
					(size 1.27 1.27)
				)
			)
		)
		(property "Value" "R_10k_0402"
			(at 297.18 186.69 0)
			(effects
				(font
					(size 1.27 1.27)
					(thickness 0.15)
				)
				(justify left bottom)
				(hide yes)
			)
		)
		(property "Footprint" "antmicro-footprints:R_0402_1005Metric"
			(at 297.18 189.23 0)
			(effects
				(font
					(size 1.27 1.27)
					(thickness 0.15)
				)
				(justify left bottom)
				(hide yes)
			)
		)
		(property "Datasheet" "https://www.bourns.com/docs/product-datasheets/cr.pdf"
			(at 297.18 191.77 0)
			(effects
				(font
					(size 1.27 1.27)
					(thickness 0.15)
				)
				(justify left bottom)
				(hide yes)
			)
		)
		(property "Description" ""
			(at 317.5 173.99 0)
			(effects
				(font
					(size 1.27 1.27)
				)
				(hide yes)
			)
		)
		(property "Manufacturer" "Bourns"
			(at 297.18 196.85 0)
			(effects
				(font
					(size 1.27 1.27)
					(thickness 0.15)
				)
				(justify left bottom)
				(hide yes)
			)
		)
		(property "MPN" "CR0402-FX-1002GLF"
			(at 297.18 194.31 0)
			(effects
				(font
					(size 1.27 1.27)
					(thickness 0.15)
				)
				(justify left bottom)
				(hide yes)
			)
		)
		(property "Val" "10k"
			(at 310.515 172.72 0)
			(effects
				(font
					(size 1.27 1.27)
					(thickness 0.15)
				)
			)
		)
		(property "License" "Apache-2.0"
			(at 297.18 199.39 0)
			(effects
				(font
					(size 1.27 1.27)
					(thickness 0.15)
				)
				(justify left bottom)
				(hide yes)
			)
		)
		(property "Author" "Antmicro"
			(at 297.18 201.93 0)
			(effects
				(font
					(size 1.27 1.27)
					(thickness 0.15)
				)
				(justify left bottom)
				(hide yes)
			)
		)
		(property "Tolerance" "1%"
			(at 297.18 184.15 0)
			(effects
				(font
					(size 1.27 1.27)
				)
				(justify left bottom)
				(hide yes)
			)
		)
		(pin "1"
		)
		(pin "2"
		)
		(instances
			(project "data-center-rdimm-ddr5-tester"
				(path ""
					(reference "R108")
					(unit 1)
				)
			)
		)
	)
	(symbol
		(lib_id "antmicropower:GND")
		(at 182.88 134.62 0)
		(unit 1)
		(exclude_from_sim no)
		(in_bom yes)
		(on_board yes)
		(dnp no)
		(fields_autoplaced yes)
		(property "Reference" "#PWR0415"
			(at 182.88 140.97 0)
			(effects
				(font
					(size 1.27 1.27)
				)
				(hide yes)
			)
		)
		(property "Value" "GND"
			(at 180.975 139.065 0)
			(effects
				(font
					(size 1.27 1.27)
					(thickness 0.15)
				)
				(justify left bottom)
			)
		)
		(property "Footprint" ""
			(at 191.77 142.24 0)
			(effects
				(font
					(size 1.27 1.27)
					(thickness 0.15)
				)
				(justify left bottom)
				(hide yes)
			)
		)
		(property "Datasheet" ""
			(at 191.77 147.32 0)
			(effects
				(font
					(size 1.27 1.27)
					(thickness 0.15)
				)
				(justify left bottom)
				(hide yes)
			)
		)
		(property "Description" ""
			(at 182.88 134.62 0)
			(effects
				(font
					(size 1.27 1.27)
				)
				(hide yes)
			)
		)
		(property "Author" "Antmicro"
			(at 191.77 139.7 0)
			(effects
				(font
					(size 1.27 1.27)
					(thickness 0.15)
				)
				(justify left bottom)
				(hide yes)
			)
		)
		(property "License" "Apache-2.0"
			(at 191.77 142.24 0)
			(effects
				(font
					(size 1.27 1.27)
					(thickness 0.15)
				)
				(justify left bottom)
				(hide yes)
			)
		)
		(pin "1"
		)
		(instances
			(project "data-center-rdimm-ddr5-tester"
				(path ""
					(reference "#PWR0415")
					(unit 1)
				)
			)
		)
	)
	(symbol
		(lib_id "antmicropower:+1V8")
		(at 52.07 100.33 0)
		(unit 1)
		(exclude_from_sim no)
		(in_bom yes)
		(on_board yes)
		(dnp no)
		(fields_autoplaced yes)
		(property "Reference" "#PWR0236"
			(at 67.31 102.87 0)
			(effects
				(font
					(size 1.27 1.27)
					(thickness 0.15)
				)
				(justify left bottom)
				(hide yes)
			)
		)
		(property "Value" "+1V8"
			(at 52.07 95.885 0)
			(effects
				(font
					(size 1.27 1.27)
					(thickness 0.15)
				)
			)
		)
		(property "Footprint" ""
			(at 67.31 107.95 0)
			(effects
				(font
					(size 1.27 1.27)
					(thickness 0.15)
				)
				(justify left bottom)
				(hide yes)
			)
		)
		(property "Datasheet" ""
			(at 67.31 110.49 0)
			(effects
				(font
					(size 1.27 1.27)
					(thickness 0.15)
				)
				(justify left bottom)
				(hide yes)
			)
		)
		(property "Description" ""
			(at 52.07 100.33 0)
			(effects
				(font
					(size 1.27 1.27)
				)
				(hide yes)
			)
		)
		(property "Author" "Antmicro"
			(at 67.31 105.41 0)
			(effects
				(font
					(size 1.27 1.27)
					(thickness 0.15)
				)
				(justify left bottom)
				(hide yes)
			)
		)
		(property "License" "Apache-2.0"
			(at 67.31 107.95 0)
			(effects
				(font
					(size 1.27 1.27)
					(thickness 0.15)
				)
				(justify left bottom)
				(hide yes)
			)
		)
		(pin "1"
		)
		(instances
			(project "data-center-rdimm-ddr5-tester"
				(path ""
					(reference "#PWR0236")
					(unit 1)
				)
			)
		)
	)
	(symbol
		(lib_id "antmicropower:PWR_FLAG")
		(at 99.06 121.92 0)
		(unit 1)
		(exclude_from_sim no)
		(in_bom yes)
		(on_board yes)
		(dnp no)
		(property "Reference" "#FLG0104"
			(at 99.06 120.015 0)
			(effects
				(font
					(size 1.27 1.27)
				)
				(hide yes)
			)
		)
		(property "Value" "PWR_FLAG"
			(at 93.98 123.19 0)
			(effects
				(font
					(size 1.27 1.27)
				)
			)
		)
		(property "Footprint" ""
			(at 99.06 121.92 0)
			(effects
				(font
					(size 1.27 1.27)
				)
				(hide yes)
			)
		)
		(property "Datasheet" ""
			(at 99.06 121.92 0)
			(effects
				(font
					(size 1.27 1.27)
				)
				(hide yes)
			)
		)
		(property "Description" ""
			(at 99.06 121.92 0)
			(effects
				(font
					(size 1.27 1.27)
				)
				(hide yes)
			)
		)
		(pin "1"
		)
		(instances
			(project "data-center-rdimm-ddr5-tester"
				(path ""
					(reference "#FLG0104")
					(unit 1)
				)
			)
		)
	)
	(symbol
		(lib_id "antmicropower:GND")
		(at 232.41 114.3 0)
		(mirror y)
		(unit 1)
		(exclude_from_sim no)
		(in_bom yes)
		(on_board yes)
		(dnp no)
		(fields_autoplaced yes)
		(property "Reference" "#PWR0409"
			(at 232.41 120.65 0)
			(effects
				(font
					(size 1.27 1.27)
				)
				(hide yes)
			)
		)
		(property "Value" "GND"
			(at 234.315 118.745 0)
			(effects
				(font
					(size 1.27 1.27)
					(thickness 0.15)
				)
				(justify left bottom)
			)
		)
		(property "Footprint" ""
			(at 223.52 121.92 0)
			(effects
				(font
					(size 1.27 1.27)
					(thickness 0.15)
				)
				(justify left bottom)
				(hide yes)
			)
		)
		(property "Datasheet" ""
			(at 223.52 127 0)
			(effects
				(font
					(size 1.27 1.27)
					(thickness 0.15)
				)
				(justify left bottom)
				(hide yes)
			)
		)
		(property "Description" ""
			(at 232.41 114.3 0)
			(effects
				(font
					(size 1.27 1.27)
				)
				(hide yes)
			)
		)
		(property "Author" "Antmicro"
			(at 223.52 119.38 0)
			(effects
				(font
					(size 1.27 1.27)
					(thickness 0.15)
				)
				(justify left bottom)
				(hide yes)
			)
		)
		(property "License" "Apache-2.0"
			(at 223.52 121.92 0)
			(effects
				(font
					(size 1.27 1.27)
					(thickness 0.15)
				)
				(justify left bottom)
				(hide yes)
			)
		)
		(pin "1"
		)
		(instances
			(project "data-center-rdimm-ddr5-tester"
				(path ""
					(reference "#PWR0409")
					(unit 1)
				)
			)
		)
	)
	(symbol
		(lib_id "antmicropower:GND")
		(at 224.79 114.3 0)
		(mirror y)
		(unit 1)
		(exclude_from_sim no)
		(in_bom yes)
		(on_board yes)
		(dnp no)
		(fields_autoplaced yes)
		(property "Reference" "#PWR0408"
			(at 224.79 120.65 0)
			(effects
				(font
					(size 1.27 1.27)
				)
				(hide yes)
			)
		)
		(property "Value" "GND"
			(at 226.695 118.745 0)
			(effects
				(font
					(size 1.27 1.27)
					(thickness 0.15)
				)
				(justify left bottom)
			)
		)
		(property "Footprint" ""
			(at 215.9 121.92 0)
			(effects
				(font
					(size 1.27 1.27)
					(thickness 0.15)
				)
				(justify left bottom)
				(hide yes)
			)
		)
		(property "Datasheet" ""
			(at 215.9 127 0)
			(effects
				(font
					(size 1.27 1.27)
					(thickness 0.15)
				)
				(justify left bottom)
				(hide yes)
			)
		)
		(property "Description" ""
			(at 224.79 114.3 0)
			(effects
				(font
					(size 1.27 1.27)
				)
				(hide yes)
			)
		)
		(property "Author" "Antmicro"
			(at 215.9 119.38 0)
			(effects
				(font
					(size 1.27 1.27)
					(thickness 0.15)
				)
				(justify left bottom)
				(hide yes)
			)
		)
		(property "License" "Apache-2.0"
			(at 215.9 121.92 0)
			(effects
				(font
					(size 1.27 1.27)
					(thickness 0.15)
				)
				(justify left bottom)
				(hide yes)
			)
		)
		(pin "1"
		)
		(instances
			(project "data-center-rdimm-ddr5-tester"
				(path ""
					(reference "#PWR0408")
					(unit 1)
				)
			)
		)
	)
	(symbol
		(lib_id "antmicroCapacitors0402:C_100n_0402")
		(at 326.39 237.49 90)
		(unit 1)
		(exclude_from_sim no)
		(in_bom yes)
		(on_board yes)
		(dnp no)
		(fields_autoplaced yes)
		(property "Reference" "C160"
			(at 328.7141 234.113 90)
			(effects
				(font
					(size 1.27 1.27)
					(thickness 0.15)
				)
				(justify right)
			)
		)
		(property "Value" "C_100n_0402"
			(at 336.55 217.17 0)
			(effects
				(font
					(size 1.27 1.27)
					(thickness 0.15)
				)
				(justify left bottom)
				(hide yes)
			)
		)
		(property "Footprint" "antmicro-footprints:C_0402_1005Metric"
			(at 339.09 217.17 0)
			(effects
				(font
					(size 1.27 1.27)
					(thickness 0.15)
				)
				(justify left bottom)
				(hide yes)
			)
		)
		(property "Datasheet" "https://www.murata.com/products/productdetail?partno=GRM155R61H104KE14%23"
			(at 341.63 217.17 0)
			(effects
				(font
					(size 1.27 1.27)
					(thickness 0.15)
				)
				(justify left bottom)
				(hide yes)
			)
		)
		(property "Description" ""
			(at 326.39 237.49 0)
			(effects
				(font
					(size 1.27 1.27)
				)
				(hide yes)
			)
		)
		(property "MPN" "GRM155R61H104KE14D"
			(at 344.17 217.17 0)
			(effects
				(font
					(size 1.27 1.27)
					(thickness 0.15)
				)
				(justify left bottom)
				(hide yes)
			)
		)
		(property "Manufacturer" "Murata"
			(at 346.71 217.17 0)
			(effects
				(font
					(size 1.27 1.27)
					(thickness 0.15)
				)
				(justify left bottom)
				(hide yes)
			)
		)
		(property "License" "Apache-2.0"
			(at 349.25 217.17 0)
			(effects
				(font
					(size 1.27 1.27)
					(thickness 0.15)
				)
				(justify left bottom)
				(hide yes)
			)
		)
		(property "Author" "Antmicro"
			(at 351.79 217.17 0)
			(effects
				(font
					(size 1.27 1.27)
					(thickness 0.15)
				)
				(justify left bottom)
				(hide yes)
			)
		)
		(property "Val" "100n"
			(at 328.7141 236.6367 90)
			(effects
				(font
					(size 1.27 1.27)
					(thickness 0.15)
				)
				(justify right)
			)
		)
		(property "Voltage" "50V"
			(at 354.33 217.17 0)
			(effects
				(font
					(size 1.27 1.27)
				)
				(justify left bottom)
				(hide yes)
			)
		)
		(property "Dielectric" "X5R"
			(at 356.87 217.17 0)
			(effects
				(font
					(size 1.27 1.27)
				)
				(justify left bottom)
				(hide yes)
			)
		)
		(pin "1"
		)
		(pin "2"
		)
		(instances
			(project "data-center-rdimm-ddr5-tester"
				(path ""
					(reference "C160")
					(unit 1)
				)
			)
		)
	)
	(symbol
		(lib_id "antmicroResistors0402:R_10k_0402")
		(at 317.5 182.88 0)
		(mirror y)
		(unit 1)
		(exclude_from_sim no)
		(in_bom yes)
		(on_board yes)
		(dnp no)
		(property "Reference" "R107"
			(at 321.31 181.61 0)
			(effects
				(font
					(size 1.27 1.27)
				)
			)
		)
		(property "Value" "R_10k_0402"
			(at 297.18 195.58 0)
			(effects
				(font
					(size 1.27 1.27)
					(thickness 0.15)
				)
				(justify left bottom)
				(hide yes)
			)
		)
		(property "Footprint" "antmicro-footprints:R_0402_1005Metric"
			(at 297.18 198.12 0)
			(effects
				(font
					(size 1.27 1.27)
					(thickness 0.15)
				)
				(justify left bottom)
				(hide yes)
			)
		)
		(property "Datasheet" "https://www.bourns.com/docs/product-datasheets/cr.pdf"
			(at 297.18 200.66 0)
			(effects
				(font
					(size 1.27 1.27)
					(thickness 0.15)
				)
				(justify left bottom)
				(hide yes)
			)
		)
		(property "Description" ""
			(at 317.5 182.88 0)
			(effects
				(font
					(size 1.27 1.27)
				)
				(hide yes)
			)
		)
		(property "Manufacturer" "Bourns"
			(at 297.18 205.74 0)
			(effects
				(font
					(size 1.27 1.27)
					(thickness 0.15)
				)
				(justify left bottom)
				(hide yes)
			)
		)
		(property "MPN" "CR0402-FX-1002GLF"
			(at 297.18 203.2 0)
			(effects
				(font
					(size 1.27 1.27)
					(thickness 0.15)
				)
				(justify left bottom)
				(hide yes)
			)
		)
		(property "Val" "10k"
			(at 310.515 181.61 0)
			(effects
				(font
					(size 1.27 1.27)
					(thickness 0.15)
				)
			)
		)
		(property "License" "Apache-2.0"
			(at 297.18 208.28 0)
			(effects
				(font
					(size 1.27 1.27)
					(thickness 0.15)
				)
				(justify left bottom)
				(hide yes)
			)
		)
		(property "Author" "Antmicro"
			(at 297.18 210.82 0)
			(effects
				(font
					(size 1.27 1.27)
					(thickness 0.15)
				)
				(justify left bottom)
				(hide yes)
			)
		)
		(property "Tolerance" "1%"
			(at 297.18 193.04 0)
			(effects
				(font
					(size 1.27 1.27)
				)
				(justify left bottom)
				(hide yes)
			)
		)
		(pin "1"
		)
		(pin "2"
		)
		(instances
			(project "data-center-rdimm-ddr5-tester"
				(path ""
					(reference "R107")
					(unit 1)
				)
			)
		)
	)
)
